FILE_TYPE = MACRO_DRAWING;
SET COLOR_WIRE YELLOW;
SET COLOR_PROP ORANGE;
SET COLOR_DOT WHITE;
SET COLOR_ARC YELLOW;
SET COLOR_BODY GREEN;
SET COLOR_NOTE PURPLE;
SET PROP_DISPLAY VALUE;
SET PAGE_NUMBER P55;
FORCEADD Q_RES..1
(-5525 1050);
FORCEPROP 1 LAST LOCATION R571
J 0
(-5575 1100);
DISPLAY 0.489362 (-5575 1100);
PAINT SKYBLUE (-5575 1100);
FORCEPROP 0 LAST $SEC 1
J 0
(-5575 1200);
DISPLAY 0.680851 (-5575 1200);
PAINT MONO (-5575 1200);
DISPLAY INVISIBLE (-5575 1200);
FORCEPROP 0 LAST CDS_SEC 1
J 0
(-5575 1200);
DISPLAY 1.021277 (-5575 1200);
DISPLAY INVISIBLE (-5575 1200);
FORCEPROP 1 LASTPIN (-5625 1050) $PN 1
J 0
(-5613 1062);
DISPLAY 0.489362 (-5613 1062);
PAINT MONO (-5613 1062);
FORCEPROP 1 LASTPIN (-5425 1050) $PN 2
J 0
(-5463 1062);
DISPLAY 0.489362 (-5463 1062);
PAINT MONO (-5463 1062);
FORCEPROP 1 LAST PACK_TYPE 0402LF
J 0
(-5275 900);
DISPLAY 0.489362 (-5275 900);
PAINT SKYBLUE (-5275 900);
FORCEPROP 1 LAST VALUE 10M
J 2
(-5550 950);
DISPLAY 0.489362 (-5550 950);
PAINT SKYBLUE (-5550 950);
FORCEPROP 1 LAST TOLERANCE 1%
J 0
(-5525 950);
DISPLAY 0.489362 (-5525 950);
PAINT SKYBLUE (-5525 950);
FORCEPROP 1 LAST MATERIAL CHIP
J 0
(-5525 900);
DISPLAY 0.489362 (-5525 900);
PAINT SKYBLUE (-5525 900);
FORCEPROP 1 LAST WATTAGE 1/16W
J 2
(-5550 900);
DISPLAY 0.489362 (-5550 900);
PAINT SKYBLUE (-5550 900);
FORCEPROP 2 LAST CDS_LIB pure_quanta
J 0
(-5525 1050);
DISPLAY INVISIBLE (-5525 1050);
FORCEPROP 1 LAST PATH I10
J 0
(-5575 1200);
DISPLAY 0.978723 (-5575 1200);
PAINT WHITE (-5575 1200);
DISPLAY INVISIBLE (-5575 1200);
FORCEPROP 1 LAST PART_NUMBER CS61002FB02
J 0
(-5750 1150);
DISPLAY 0.489362 (-5750 1150);
PAINT SKYBLUE (-5750 1150);
DISPLAY INVISIBLE (-5750 1150);
FORCEADD UNIVERSAL_GND..1
(-5900 1250);
FORCEPROP 3 LASTPIN (-5900 1300) SIG_NAME GND\g
J 0
(-5890 1310);
DISPLAY 0.659574 (-5890 1310);
PAINT MONO (-5890 1310);
DISPLAY INVISIBLE (-5890 1310);
FORCEPROP 2 LAST CDS_LIB pure_quanta_power
J 0
(-5900 1250);
DISPLAY INVISIBLE (-5900 1250);
FORCEPROP 1 LAST HDL_POWER GND
J 1
(-5875 1175);
DISPLAY 0.872340 (-5875 1175);
PAINT GREEN (-5875 1175);
DISPLAY INVISIBLE (-5875 1175);
FORCEPROP 1 LAST PATH I11
J 0
(-5825 1250);
DISPLAY 0.872340 (-5825 1250);
PAINT AQUA (-5825 1250);
DISPLAY INVISIBLE (-5825 1250);
FORCEADD Q_XTAL_4P_13BI_24GND..1
(-5525 1575);
FORCEPROP 1 LAST LOCATION Y4
J 0
(-5658 1941);
DISPLAY 0.489362 (-5658 1941);
PAINT SKYBLUE (-5658 1941);
FORCEPROP 0 LAST $SEC 1
J 0
(-5650 2075);
DISPLAY 0.680851 (-5650 2075);
PAINT MONO (-5650 2075);
DISPLAY INVISIBLE (-5650 2075);
FORCEPROP 0 LAST CDS_SEC 1
J 0
(-5650 2075);
DISPLAY 1.021277 (-5650 2075);
DISPLAY INVISIBLE (-5650 2075);
FORCEPROP 0 LASTPIN (-5800 1450) $PN 2
J 2
(-5810 1460);
DISPLAY 0.489362 (-5810 1460);
PAINT MONO (-5810 1460);
FORCEPROP 0 LASTPIN (-5250 1450) $PN 4
J 0
(-5240 1460);
DISPLAY 0.489362 (-5240 1460);
PAINT MONO (-5240 1460);
FORCEPROP 0 LASTPIN (-5800 1650) $PN 1
J 2
(-5810 1660);
DISPLAY 0.489362 (-5810 1660);
PAINT MONO (-5810 1660);
FORCEPROP 0 LASTPIN (-5250 1650) $PN 3
J 0
(-5240 1660);
DISPLAY 0.489362 (-5240 1660);
PAINT MONO (-5240 1660);
FORCEPROP 2 LAST VALUE 48MHZ
J 0
(-5650 1975);
DISPLAY 0.489362 (-5650 1975);
PAINT SKYBLUE (-5650 1975);
FORCEPROP 2 LAST PART_TYPE SMLF
J 0
(-5650 2025);
DISPLAY 1.021277 (-5650 2025);
FORCEPROP 1 LAST MATERIAL MISC
J 0
(-5658 1754);
DISPLAY 0.489362 (-5658 1754);
PAINT SKYBLUE (-5658 1754);
FORCEPROP 1 LAST CDS_LMAN_SYM_OUTLINE -125,175,125,-175
J 0
(-5525 1575);
DISPLAY 0.468085 (-5525 1575);
PAINT GREEN (-5525 1575);
DISPLAY INVISIBLE (-5525 1575);
FORCEPROP 1 LAST PIN_NAMES_ROTATE True
J 0
(-5525 1575);
DISPLAY 0.489362 (-5525 1575);
PAINT GREEN (-5525 1575);
DISPLAY INVISIBLE (-5525 1575);
FORCEPROP 2 LAST CDS_LIB pure_quanta
J 0
(-5525 1575);
DISPLAY INVISIBLE (-5525 1575);
FORCEPROP 1 LAST PATH I12
J 0
(-5400 1400);
DISPLAY 0.723404 (-5400 1400);
PAINT GREEN (-5400 1400);
DISPLAY INVISIBLE (-5400 1400);
FORCEPROP 1 LAST PART_NUMBER BG648000076
J 0
(-5658 1850);
DISPLAY 0.489362 (-5658 1850);
PAINT SKYBLUE (-5658 1850);
DISPLAY INVISIBLE (-5658 1850);
FORCEADD UNIVERSAL_GND..1
(-5125 1250);
FORCEPROP 3 LASTPIN (-5125 1300) SIG_NAME GND\g
J 0
(-5115 1310);
DISPLAY 0.659574 (-5115 1310);
PAINT MONO (-5115 1310);
DISPLAY INVISIBLE (-5115 1310);
FORCEPROP 2 LAST CDS_LIB pure_quanta_power
J 0
(-5125 1250);
DISPLAY INVISIBLE (-5125 1250);
FORCEPROP 1 LAST HDL_POWER GND
J 1
(-5100 1175);
DISPLAY 0.872340 (-5100 1175);
PAINT GREEN (-5100 1175);
DISPLAY INVISIBLE (-5100 1175);
FORCEPROP 1 LAST PATH I13
J 0
(-5050 1250);
DISPLAY 0.872340 (-5050 1250);
PAINT AQUA (-5050 1250);
DISPLAY INVISIBLE (-5050 1250);
FORCEADD UNIVERSAL_GND..1
(-4900 525);
FORCEPROP 3 LASTPIN (-4900 575) SIG_NAME GND\g
J 0
(-4890 585);
DISPLAY 0.659574 (-4890 585);
PAINT MONO (-4890 585);
DISPLAY INVISIBLE (-4890 585);
FORCEPROP 2 LAST CDS_LIB pure_quanta_power
J 0
(-4900 525);
DISPLAY INVISIBLE (-4900 525);
FORCEPROP 1 LAST HDL_POWER GND
J 1
(-4875 450);
DISPLAY 0.872340 (-4875 450);
PAINT GREEN (-4875 450);
DISPLAY INVISIBLE (-4875 450);
FORCEPROP 1 LAST PATH I14
J 0
(-4825 525);
DISPLAY 0.872340 (-4825 525);
PAINT AQUA (-4825 525);
DISPLAY INVISIBLE (-4825 525);
FORCEADD Q_CAP..1
(-4900 825);
FORCEPROP 1 LAST LOCATION C237
J 0
(-4850 925);
DISPLAY 0.489362 (-4850 925);
PAINT SKYBLUE (-4850 925);
FORCEPROP 0 LAST $SEC 1
J 0
(-4850 975);
DISPLAY 0.680851 (-4850 975);
PAINT MONO (-4850 975);
DISPLAY INVISIBLE (-4850 975);
FORCEPROP 0 LAST CDS_SEC 1
J 0
(-4850 975);
DISPLAY 1.021277 (-4850 975);
DISPLAY INVISIBLE (-4850 975);
FORCEPROP 1 LASTPIN (-4900 925) $PN 1
J 0
(-4890 905);
DISPLAY 0.489362 (-4890 905);
PAINT MONO (-4890 905);
FORCEPROP 1 LASTPIN (-4900 725) $PN 2
J 0
(-4890 705);
DISPLAY 0.489362 (-4890 705);
PAINT MONO (-4890 705);
FORCEPROP 1 LAST TOLERANCE 0.1PF
J 0
(-4850 775);
DISPLAY 0.489362 (-4850 775);
PAINT SKYBLUE (-4850 775);
FORCEPROP 1 LAST VOLTAGE 50V
J 0
(-4850 825);
DISPLAY 0.489362 (-4850 825);
PAINT SKYBLUE (-4850 825);
FORCEPROP 1 LAST MATERIAL NPO
J 0
(-4850 725);
DISPLAY 0.489362 (-4850 725);
PAINT SKYBLUE (-4850 725);
FORCEPROP 1 LAST PACK_TYPE C0402
J 0
(-4850 625);
DISPLAY 0.489362 (-4850 625);
PAINT SKYBLUE (-4850 625);
FORCEPROP 1 LAST VALUE 2.7PF
J 0
(-4850 875);
DISPLAY 0.489362 (-4850 875);
PAINT SKYBLUE (-4850 875);
FORCEPROP 2 LAST CDS_LIB pure_quanta
J 0
(-4900 825);
DISPLAY INVISIBLE (-4900 825);
FORCEPROP 1 LAST PATH I15
J 0
(-4850 975);
DISPLAY 0.978723 (-4850 975);
PAINT WHITE (-4850 975);
DISPLAY INVISIBLE (-4850 975);
FORCEPROP 1 LAST PART_NUMBER CH-276B0B00
J 0
(-4850 675);
DISPLAY 0.489362 (-4850 675);
PAINT SKYBLUE (-4850 675);
DISPLAY INVISIBLE (-4850 675);
FORCEADD OFFPAGE..2
(-1150 2125);
FORCEPROP 2 LAST $XR0 55 
J 0
(-961 2125);
DISPLAY 0.638298 (-961 2125);
PAINT MONO (-961 2125);
FORCEPROP 2 LAST CDS_LIB standard
J 0
(-1150 2125);
DISPLAY INVISIBLE (-1150 2125);
FORCEPROP 1 LAST OFFPAGE TRUE
J 0
(-825 2000);
DISPLAY 0.872340 (-825 2000);
PAINT GREEN (-825 2000);
DISPLAY INVISIBLE (-825 2000);
FORCEPROP 1 LAST COMMENT_BODY TRUE
J 0
(-1195 2030);
DISPLAY 0.872340 (-1195 2030);
PAINT GREEN (-1195 2030);
DISPLAY INVISIBLE (-1195 2030);
FORCEPROP 2 LAST PATH I16
J 0
(-975 2200);
DISPLAY 1.021277 (-975 2200);
DISPLAY INVISIBLE (-975 2200);
FORCEADD OFFPAGE..2
(-1150 2175);
FORCEPROP 2 LAST $XR0 55 
J 0
(-961 2175);
DISPLAY 0.638298 (-961 2175);
PAINT MONO (-961 2175);
FORCEPROP 2 LAST CDS_LIB standard
J 2
(-1150 2175);
DISPLAY INVISIBLE (-1150 2175);
FORCEPROP 1 LAST OFFPAGE TRUE
J 0
(-825 2050);
DISPLAY 0.872340 (-825 2050);
PAINT GREEN (-825 2050);
DISPLAY INVISIBLE (-825 2050);
FORCEPROP 1 LAST COMMENT_BODY TRUE
J 0
(-1195 2080);
DISPLAY 0.872340 (-1195 2080);
PAINT GREEN (-1195 2080);
DISPLAY INVISIBLE (-1195 2080);
FORCEPROP 2 LAST PATH I17
J 0
(-975 2250);
DISPLAY 1.021277 (-975 2250);
DISPLAY INVISIBLE (-975 2250);
FORCEADD OFFPAGE..2
(-4500 2100);
FORCEPROP 2 LAST $XR0 55 
J 0
(-4311 2100);
DISPLAY 0.638298 (-4311 2100);
PAINT MONO (-4311 2100);
FORCEPROP 2 LAST CDS_LIB standard
J 0
(-4500 2100);
DISPLAY INVISIBLE (-4500 2100);
FORCEPROP 1 LAST OFFPAGE TRUE
J 0
(-4175 1975);
DISPLAY 0.872340 (-4175 1975);
PAINT GREEN (-4175 1975);
DISPLAY INVISIBLE (-4175 1975);
FORCEPROP 1 LAST COMMENT_BODY TRUE
J 0
(-4545 2005);
DISPLAY 0.872340 (-4545 2005);
PAINT GREEN (-4545 2005);
DISPLAY INVISIBLE (-4545 2005);
FORCEPROP 2 LAST PATH I18
J 0
(-4325 2175);
DISPLAY 1.021277 (-4325 2175);
DISPLAY INVISIBLE (-4325 2175);
FORCEADD GENOA_SP5..21
(-4375 4475);
FORCEPROP 1 LAST LOCATION U26
J 0
(-5470 6502);
DISPLAY 0.489362 (-5470 6502);
PAINT SKYBLUE (-5470 6502);
FORCEPROP 0 LAST $SEC 21
J 0
(-5450 6550);
DISPLAY 0.680851 (-5450 6550);
PAINT MONO (-5450 6550);
DISPLAY INVISIBLE (-5450 6550);
FORCEPROP 0 LAST CDS_SEC 21
J 0
(-5450 6175);
DISPLAY 1.021277 (-5450 6175);
DISPLAY INVISIBLE (-5450 6175);
FORCEPROP 0 LASTPIN (-5625 3475) $PN DE36
J 2
(-5635 3485);
DISPLAY 0.489362 (-5635 3485);
PAINT MONO (-5635 3485);
FORCEPROP 0 LASTPIN (-5625 3425) $PN DF36
J 2
(-5635 3435);
DISPLAY 0.489362 (-5635 3435);
PAINT MONO (-5635 3435);
FORCEPROP 0 LASTPIN (-5625 3375) $PN DF40
J 2
(-5635 3385);
DISPLAY 0.489362 (-5635 3385);
PAINT MONO (-5635 3385);
FORCEPROP 0 LASTPIN (-5625 3325) $PN DE40
J 2
(-5635 3335);
DISPLAY 0.489362 (-5635 3335);
PAINT MONO (-5635 3335);
FORCEPROP 0 LASTPIN (-5625 2725) $PN DH4
J 2
(-5635 2735);
DISPLAY 0.489362 (-5635 2735);
PAINT MONO (-5635 2735);
FORCEPROP 0 LASTPIN (-5625 3175) $PN DF33
J 2
(-5635 3185);
DISPLAY 0.489362 (-5635 3185);
PAINT MONO (-5635 3185);
FORCEPROP 0 LASTPIN (-5625 3125) $PN DE32
J 2
(-5635 3135);
DISPLAY 0.489362 (-5635 3135);
PAINT MONO (-5635 3135);
FORCEPROP 0 LASTPIN (-5625 3075) $PN DG11
J 2
(-5635 3085);
DISPLAY 0.489362 (-5635 3085);
PAINT MONO (-5635 3085);
FORCEPROP 0 LASTPIN (-5625 3025) $PN DJ29
J 2
(-5635 3035);
DISPLAY 0.489362 (-5635 3035);
PAINT MONO (-5635 3035);
FORCEPROP 0 LASTPIN (-5625 2975) $PN DH30
J 2
(-5635 2985);
DISPLAY 0.489362 (-5635 2985);
PAINT MONO (-5635 2985);
FORCEPROP 0 LASTPIN (-5625 2925) $PN DE30
J 2
(-5635 2935);
DISPLAY 0.489362 (-5635 2935);
PAINT MONO (-5635 2935);
FORCEPROP 0 LASTPIN (-5625 2875) $PN DF31
J 2
(-5635 2885);
DISPLAY 0.489362 (-5635 2885);
PAINT MONO (-5635 2885);
FORCEPROP 0 LASTPIN (-5625 2825) $PN DG31
J 2
(-5635 2835);
DISPLAY 0.489362 (-5635 2835);
PAINT MONO (-5635 2835);
FORCEPROP 0 LASTPIN (-5625 2775) $PN DG32
J 2
(-5635 2785);
DISPLAY 0.489362 (-5635 2785);
PAINT MONO (-5635 2785);
FORCEPROP 0 LASTPIN (-5625 3275) $PN DH16
J 2
(-5635 3285);
DISPLAY 0.489362 (-5635 3285);
PAINT MONO (-5635 3285);
FORCEPROP 0 LASTPIN (-5625 3225) $PN DH15
J 2
(-5635 3235);
DISPLAY 0.489362 (-5635 3235);
PAINT MONO (-5635 3235);
FORCEPROP 0 LASTPIN (-3125 2975) $PN A14
J 0
(-3115 2985);
DISPLAY 0.489362 (-3115 2985);
PAINT MONO (-3115 2985);
FORCEPROP 0 LASTPIN (-3125 2925) $PN C14
J 0
(-3115 2935);
DISPLAY 0.489362 (-3115 2935);
PAINT MONO (-3115 2935);
FORCEPROP 0 LASTPIN (-3125 2875) $PN A13
J 0
(-3115 2885);
DISPLAY 0.489362 (-3115 2885);
PAINT MONO (-3115 2885);
FORCEPROP 0 LASTPIN (-3125 2825) $PN B16
J 0
(-3115 2835);
DISPLAY 0.489362 (-3115 2835);
PAINT MONO (-3115 2835);
FORCEPROP 0 LASTPIN (-3125 5425) $PN B63
J 0
(-3115 5435);
DISPLAY 0.489362 (-3115 5435);
PAINT MONO (-3115 5435);
FORCEPROP 0 LASTPIN (-5625 4875) $PN DJ35
J 2
(-5635 4885);
DISPLAY 0.489362 (-5635 4885);
PAINT MONO (-5635 4885);
FORCEPROP 0 LASTPIN (-3125 4875) $PN A7
J 0
(-3115 4885);
DISPLAY 0.489362 (-3115 4885);
PAINT MONO (-3115 4885);
FORCEPROP 0 LASTPIN (-3125 4925) $PN A8
J 0
(-3115 4935);
DISPLAY 0.489362 (-3115 4935);
PAINT MONO (-3115 4935);
FORCEPROP 0 LASTPIN (-3125 4725) $PN C6
J 0
(-3115 4735);
DISPLAY 0.489362 (-3115 4735);
PAINT MONO (-3115 4735);
FORCEPROP 0 LASTPIN (-3125 4775) $PN B6
J 0
(-3115 4785);
DISPLAY 0.489362 (-3115 4785);
PAINT MONO (-3115 4785);
FORCEPROP 0 LASTPIN (-3125 4575) $PN A11
J 0
(-3115 4585);
DISPLAY 0.489362 (-3115 4585);
PAINT MONO (-3115 4585);
FORCEPROP 0 LASTPIN (-3125 4625) $PN A10
J 0
(-3115 4635);
DISPLAY 0.489362 (-3115 4635);
PAINT MONO (-3115 4635);
FORCEPROP 0 LASTPIN (-3125 4425) $PN C12
J 0
(-3115 4435);
DISPLAY 0.489362 (-3115 4435);
PAINT MONO (-3115 4435);
FORCEPROP 0 LASTPIN (-3125 4475) $PN B12
J 0
(-3115 4485);
DISPLAY 0.489362 (-3115 4485);
PAINT MONO (-3115 4485);
FORCEPROP 0 LASTPIN (-3125 4275) $PN C9
J 0
(-3115 4285);
DISPLAY 0.489362 (-3115 4285);
PAINT MONO (-3115 4285);
FORCEPROP 0 LASTPIN (-3125 4325) $PN B9
J 0
(-3115 4335);
DISPLAY 0.489362 (-3115 4335);
PAINT MONO (-3115 4335);
FORCEPROP 0 LASTPIN (-3125 4125) $PN DJ42
J 0
(-3115 4135);
DISPLAY 0.489362 (-3115 4135);
PAINT MONO (-3115 4135);
FORCEPROP 0 LASTPIN (-3125 4175) $PN DJ41
J 0
(-3115 4185);
DISPLAY 0.489362 (-3115 4185);
PAINT MONO (-3115 4185);
FORCEPROP 0 LASTPIN (-3125 3975) $PN DJ44
J 0
(-3115 3985);
DISPLAY 0.489362 (-3115 3985);
PAINT MONO (-3115 3985);
FORCEPROP 0 LASTPIN (-3125 4025) $PN DJ45
J 0
(-3115 4035);
DISPLAY 0.489362 (-3115 4035);
PAINT MONO (-3115 4035);
FORCEPROP 0 LASTPIN (-3125 3825) $PN DJ54
J 0
(-3115 3835);
DISPLAY 0.489362 (-3115 3835);
PAINT MONO (-3115 3835);
FORCEPROP 0 LASTPIN (-3125 3875) $PN DJ53
J 0
(-3115 3885);
DISPLAY 0.489362 (-3115 3885);
PAINT MONO (-3115 3885);
FORCEPROP 0 LASTPIN (-3125 3675) $PN DJ47
J 0
(-3115 3685);
DISPLAY 0.489362 (-3115 3685);
PAINT MONO (-3115 3685);
FORCEPROP 0 LASTPIN (-3125 3725) $PN DJ48
J 0
(-3115 3735);
DISPLAY 0.489362 (-3115 3735);
PAINT MONO (-3115 3735);
FORCEPROP 0 LASTPIN (-3125 3525) $PN DJ50
J 0
(-3115 3535);
DISPLAY 0.489362 (-3115 3535);
PAINT MONO (-3115 3535);
FORCEPROP 0 LASTPIN (-3125 3575) $PN DJ51
J 0
(-3115 3585);
DISPLAY 0.489362 (-3115 3585);
PAINT MONO (-3115 3585);
FORCEPROP 0 LASTPIN (-5625 4025) $PN DG12
J 2
(-5635 4035);
DISPLAY 0.489362 (-5635 4035);
PAINT MONO (-5635 4035);
FORCEPROP 0 LASTPIN (-5625 3975) $PN DH12
J 2
(-5635 3985);
DISPLAY 0.489362 (-5635 3985);
PAINT MONO (-5635 3985);
FORCEPROP 0 LASTPIN (-5625 3925) $PN DJ21
J 2
(-5635 3935);
DISPLAY 0.489362 (-5635 3935);
PAINT MONO (-5635 3935);
FORCEPROP 0 LASTPIN (-5625 3875) $PN DJ20
J 2
(-5635 3885);
DISPLAY 0.489362 (-5635 3885);
PAINT MONO (-5635 3885);
FORCEPROP 0 LASTPIN (-5625 4425) $PN A71
J 2
(-5635 4435);
DISPLAY 0.489362 (-5635 4435);
PAINT MONO (-5635 4435);
FORCEPROP 0 LASTPIN (-5625 4375) $PN B71
J 2
(-5635 4385);
DISPLAY 0.489362 (-5635 4385);
PAINT MONO (-5635 4385);
FORCEPROP 0 LASTPIN (-5625 4325) $PN C7
J 2
(-5635 4335);
DISPLAY 0.489362 (-5635 4335);
PAINT MONO (-5635 4335);
FORCEPROP 0 LASTPIN (-5625 4275) $PN A5
J 2
(-5635 4285);
DISPLAY 0.489362 (-5635 4285);
PAINT MONO (-5635 4285);
FORCEPROP 0 LASTPIN (-5625 4225) $PN C72
J 2
(-5635 4235);
DISPLAY 0.489362 (-5635 4235);
PAINT MONO (-5635 4235);
FORCEPROP 0 LASTPIN (-5625 4175) $PN B72
J 2
(-5635 4185);
DISPLAY 0.489362 (-5635 4185);
PAINT MONO (-5635 4185);
FORCEPROP 0 LASTPIN (-5625 4125) $PN A4
J 2
(-5635 4135);
DISPLAY 0.489362 (-5635 4135);
PAINT MONO (-5635 4135);
FORCEPROP 0 LASTPIN (-5625 4075) $PN B4
J 2
(-5635 4085);
DISPLAY 0.489362 (-5635 4085);
PAINT MONO (-5635 4085);
FORCEPROP 0 LASTPIN (-5625 4675) $PN DJ31
J 2
(-5635 4685);
DISPLAY 0.489362 (-5635 4685);
PAINT MONO (-5635 4685);
FORCEPROP 0 LASTPIN (-3125 5325) $PN B64
J 0
(-3115 5335);
DISPLAY 0.489362 (-3115 5335);
PAINT MONO (-3115 5335);
FORCEPROP 0 LASTPIN (-3125 5175) $PN D18
J 0
(-3115 5185);
DISPLAY 0.489362 (-3115 5185);
PAINT MONO (-3115 5185);
FORCEPROP 0 LASTPIN (-3125 5125) $PN DG36
J 0
(-3115 5135);
DISPLAY 0.489362 (-3115 5135);
PAINT MONO (-3115 5135);
FORCEPROP 0 LASTPIN (-5625 5625) $PN DH7
J 2
(-5635 5635);
DISPLAY 0.489362 (-5635 5635);
PAINT MONO (-5635 5635);
FORCEPROP 0 LASTPIN (-5625 5425) $PN DJ8
J 2
(-5635 5435);
DISPLAY 0.489362 (-5635 5435);
PAINT MONO (-5635 5435);
FORCEPROP 0 LASTPIN (-3125 5625) $PN DH36
J 0
(-3115 5635);
DISPLAY 0.489362 (-3115 5635);
PAINT MONO (-3115 5635);
FORCEPROP 0 LASTPIN (-3125 5775) $PN D69
J 0
(-3115 5785);
DISPLAY 0.489362 (-3115 5785);
PAINT MONO (-3115 5785);
FORCEPROP 0 LASTPIN (-3125 6075) $PN A20
J 0
(-3115 6085);
DISPLAY 0.489362 (-3115 6085);
PAINT MONO (-3115 6085);
FORCEPROP 0 LASTPIN (-3125 6125) $PN A19
J 0
(-3115 6135);
DISPLAY 0.489362 (-3115 6135);
PAINT MONO (-3115 6135);
FORCEPROP 0 LASTPIN (-3125 5875) $PN B67
J 0
(-3115 5885);
DISPLAY 0.489362 (-3115 5885);
PAINT MONO (-3115 5885);
FORCEPROP 0 LASTPIN (-5625 5525) $PN DG10
J 2
(-5635 5535);
DISPLAY 0.489362 (-5635 5535);
PAINT MONO (-5635 5535);
FORCEPROP 0 LASTPIN (-3125 5975) $PN DH9
J 0
(-3115 5985);
DISPLAY 0.489362 (-3115 5985);
PAINT MONO (-3115 5985);
FORCEPROP 0 LASTPIN (-3125 3175) $PN B14
J 0
(-3115 3185);
DISPLAY 0.489362 (-3115 3185);
PAINT MONO (-3115 3185);
FORCEPROP 0 LASTPIN (-3125 3125) $PN D14
J 0
(-3115 3135);
DISPLAY 0.489362 (-3115 3135);
PAINT MONO (-3115 3135);
FORCEPROP 0 LASTPIN (-5625 3625) $PN D15
J 2
(-5635 3635);
DISPLAY 0.489362 (-5635 3635);
PAINT MONO (-5635 3635);
FORCEPROP 0 LASTPIN (-5625 3575) $PN B15
J 2
(-5635 3585);
DISPLAY 0.489362 (-5635 3585);
PAINT MONO (-5635 3585);
FORCEPROP 0 LASTPIN (-5625 5725) $PN DJ5
J 2
(-5635 5735);
DISPLAY 0.489362 (-5635 5735);
PAINT MONO (-5635 5735);
FORCEPROP 0 LASTPIN (-5625 5775) $PN DG4
J 2
(-5635 5785);
DISPLAY 0.489362 (-5635 5785);
PAINT MONO (-5635 5785);
FORCEPROP 0 LASTPIN (-5625 3725) $PN DJ11
J 2
(-5635 3735);
DISPLAY 0.489362 (-5635 3735);
PAINT MONO (-5635 3735);
FORCEPROP 0 LASTPIN (-5625 5575) $PN DH6
J 2
(-5635 5585);
DISPLAY 0.489362 (-5635 5585);
PAINT MONO (-5635 5585);
FORCEPROP 0 LASTPIN (-3125 5525) $PN DJ10
J 0
(-3115 5535);
DISPLAY 0.489362 (-3115 5535);
PAINT MONO (-3115 5535);
FORCEPROP 0 LASTPIN (-5625 5075) $PN DJ14
J 2
(-5635 5085);
DISPLAY 0.489362 (-5635 5085);
PAINT MONO (-5635 5085);
FORCEPROP 0 LASTPIN (-5625 5025) $PN DJ13
J 2
(-5635 5035);
DISPLAY 0.489362 (-5635 5035);
PAINT MONO (-5635 5035);
FORCEPROP 0 LASTPIN (-5625 5275) $PN DJ17
J 2
(-5635 5285);
DISPLAY 0.489362 (-5635 5285);
PAINT MONO (-5635 5285);
FORCEPROP 0 LASTPIN (-5625 5225) $PN DJ16
J 2
(-5635 5235);
DISPLAY 0.489362 (-5635 5235);
PAINT MONO (-5635 5235);
FORCEPROP 2 LAST PART_TYPE SMLF
J 0
(-5450 6125);
DISPLAY 1.021277 (-5450 6125);
FORCEPROP 1 LAST MATERIAL IO
J 0
(-5470 6308);
DISPLAY 0.489362 (-5470 6308);
PAINT SKYBLUE (-5470 6308);
FORCEPROP 2 LAST VALUE SOCKET6096_13568-001
J 0
(-5450 6025);
DISPLAY 0.489362 (-5450 6025);
PAINT SKYBLUE (-5450 6025);
FORCEPROP 1 LAST NEEDS_NO_SIZE TRUE
J 0
(-4375 4475);
DISPLAY 0.723404 (-4375 4475);
PAINT GREEN (-4375 4475);
DISPLAY INVISIBLE (-4375 4475);
FORCEPROP 1 LAST CDS_LMAN_SYM_OUTLINE -1100,1800,1100,-1800
J 0
(-4375 4475);
DISPLAY 0.468085 (-4375 4475);
PAINT GREEN (-4375 4475);
DISPLAY INVISIBLE (-4375 4475);
FORCEPROP 2 LAST CDS_LIB pure_quanta
J 0
(-4375 4475);
DISPLAY INVISIBLE (-4375 4475);
FORCEPROP 1 LAST PATH I182
J 0
(-4375 4475);
DISPLAY 0.723404 (-4375 4475);
PAINT GREEN (-4375 4475);
DISPLAY INVISIBLE (-4375 4475);
FORCEPROP 1 LAST PART_NUMBER DGA^6000030
J 0
(-5470 6407);
DISPLAY 0.489362 (-5470 6407);
PAINT SKYBLUE (-5470 6407);
DISPLAY INVISIBLE (-5470 6407);
FORCEADD OFFPAGE..1
R 2
(-1000 5525);
FORCEPROP 2 LAST $XR1 28 
J 0
(-694 5525);
DISPLAY 0.638298 (-694 5525);
PAINT MONO (-694 5525);
FORCEPROP 2 LAST $XR0 155 
J 0
(-814 5525);
DISPLAY 0.638298 (-814 5525);
PAINT MONO (-814 5525);
FORCEPROP 2 LAST CDS_LIB standard
J 2
(-1000 5525);
DISPLAY INVISIBLE (-1000 5525);
FORCEPROP 1 LAST OFFPAGE TRUE
J 2
(-1325 5400);
DISPLAY 0.872340 (-1325 5400);
PAINT GREEN (-1325 5400);
DISPLAY INVISIBLE (-1325 5400);
FORCEPROP 1 LAST COMMENT_BODY TRUE
J 2
(-1125 5425);
DISPLAY 0.872340 (-1125 5425);
PAINT GREEN (-1125 5425);
DISPLAY INVISIBLE (-1125 5425);
FORCEPROP 2 LAST PATH I183
J 0
(-675 5575);
DISPLAY 1.021277 (-675 5575);
DISPLAY INVISIBLE (-675 5575);
FORCEADD OFFPAGE..1
R 2
(-2300 6125);
FORCEPROP 2 LAST $XR0 28 
J 0
(-2114 6125);
DISPLAY 0.638298 (-2114 6125);
PAINT MONO (-2114 6125);
FORCEPROP 2 LAST CDS_LIB standard
J 2
(-2300 6125);
DISPLAY INVISIBLE (-2300 6125);
FORCEPROP 1 LAST OFFPAGE TRUE
J 2
(-2625 6000);
DISPLAY 0.872340 (-2625 6000);
PAINT GREEN (-2625 6000);
DISPLAY INVISIBLE (-2625 6000);
FORCEPROP 1 LAST COMMENT_BODY TRUE
J 2
(-2425 6025);
DISPLAY 0.872340 (-2425 6025);
PAINT GREEN (-2425 6025);
DISPLAY INVISIBLE (-2425 6025);
FORCEPROP 2 LAST PATH I185
J 0
(-2100 6175);
DISPLAY 1.021277 (-2100 6175);
DISPLAY INVISIBLE (-2100 6175);
FORCEADD OFFPAGE..1
R 2
(-2300 6075);
FORCEPROP 2 LAST $XR0 28 
J 0
(-2114 6075);
DISPLAY 0.638298 (-2114 6075);
PAINT MONO (-2114 6075);
FORCEPROP 2 LAST CDS_LIB standard
J 0
(-2300 6075);
DISPLAY INVISIBLE (-2300 6075);
FORCEPROP 1 LAST OFFPAGE TRUE
J 2
(-2625 5950);
DISPLAY 0.872340 (-2625 5950);
PAINT GREEN (-2625 5950);
DISPLAY INVISIBLE (-2625 5950);
FORCEPROP 1 LAST COMMENT_BODY TRUE
J 2
(-2425 5975);
DISPLAY 0.872340 (-2425 5975);
PAINT GREEN (-2425 5975);
DISPLAY INVISIBLE (-2425 5975);
FORCEPROP 2 LAST PATH I186
J 0
(-2100 6125);
DISPLAY 1.021277 (-2100 6125);
DISPLAY INVISIBLE (-2100 6125);
FORCEADD OFFPAGE..3
(-2175 5775);
FORCEPROP 2 LAST $XR3 78 
J 0
(-1691 5775);
DISPLAY 0.638298 (-1691 5775);
PAINT MONO (-1691 5775);
FORCEPROP 2 LAST $XR2 85 
J 0
(-1781 5775);
DISPLAY 0.638298 (-1781 5775);
PAINT MONO (-1781 5775);
FORCEPROP 2 LAST $XR1 81 
J 0
(-1871 5775);
DISPLAY 0.638298 (-1871 5775);
PAINT MONO (-1871 5775);
FORCEPROP 2 LAST $XR0 55 
J 0
(-1961 5775);
DISPLAY 0.638298 (-1961 5775);
PAINT MONO (-1961 5775);
FORCEPROP 2 LAST CDS_LIB standard
J 2
(-2175 5775);
DISPLAY INVISIBLE (-2175 5775);
FORCEPROP 1 LAST OFFPAGE TRUE
J 0
(-1850 5650);
DISPLAY 0.872340 (-1850 5650);
PAINT GREEN (-1850 5650);
DISPLAY INVISIBLE (-1850 5650);
FORCEPROP 1 LAST COMMENT_BODY TRUE
J 0
(-2225 5675);
DISPLAY 0.872340 (-2225 5675);
PAINT PEACH (-2225 5675);
DISPLAY INVISIBLE (-2225 5675);
FORCEPROP 2 LAST PATH I187
J 0
(-1625 5825);
DISPLAY 1.021277 (-1625 5825);
DISPLAY INVISIBLE (-1625 5825);
FORCEADD OFFPAGE..3
(-2175 5875);
FORCEPROP 2 LAST $XR2 85 
J 0
(-1781 5875);
DISPLAY 0.638298 (-1781 5875);
PAINT MONO (-1781 5875);
FORCEPROP 2 LAST $XR1 81 
J 0
(-1871 5875);
DISPLAY 0.638298 (-1871 5875);
PAINT MONO (-1871 5875);
FORCEPROP 2 LAST $XR0 55 
J 0
(-1961 5875);
DISPLAY 0.638298 (-1961 5875);
PAINT MONO (-1961 5875);
FORCEPROP 2 LAST CDS_LIB standard
J 2
(-2175 5875);
DISPLAY INVISIBLE (-2175 5875);
FORCEPROP 1 LAST OFFPAGE TRUE
J 0
(-1850 5750);
DISPLAY 0.872340 (-1850 5750);
PAINT GREEN (-1850 5750);
DISPLAY INVISIBLE (-1850 5750);
FORCEPROP 1 LAST COMMENT_BODY TRUE
J 0
(-2225 5775);
DISPLAY 0.872340 (-2225 5775);
PAINT PEACH (-2225 5775);
DISPLAY INVISIBLE (-2225 5775);
FORCEPROP 2 LAST PATH I188
J 0
(-1750 5925);
DISPLAY 1.021277 (-1750 5925);
DISPLAY INVISIBLE (-1750 5925);
FORCEADD OFFPAGE..1
R 2
(-2300 5425);
FORCEPROP 2 LAST $XR1 81 
J 0
(-2024 5425);
DISPLAY 0.638298 (-2024 5425);
PAINT MONO (-2024 5425);
FORCEPROP 2 LAST $XR0 55 
J 0
(-2114 5425);
DISPLAY 0.638298 (-2114 5425);
PAINT MONO (-2114 5425);
FORCEPROP 2 LAST CDS_LIB standard
J 0
(-2300 5425);
DISPLAY INVISIBLE (-2300 5425);
FORCEPROP 1 LAST OFFPAGE TRUE
J 2
(-2625 5300);
DISPLAY 0.872340 (-2625 5300);
PAINT GREEN (-2625 5300);
DISPLAY INVISIBLE (-2625 5300);
FORCEPROP 1 LAST COMMENT_BODY TRUE
J 2
(-2425 5325);
DISPLAY 0.872340 (-2425 5325);
PAINT GREEN (-2425 5325);
DISPLAY INVISIBLE (-2425 5325);
FORCEPROP 2 LAST PATH I189
J 0
(-2000 5475);
DISPLAY 1.021277 (-2000 5475);
DISPLAY INVISIBLE (-2000 5475);
FORCEADD OFFPAGE..2
(-4500 2150);
FORCEPROP 2 LAST $XR0 55 
J 0
(-4311 2150);
DISPLAY 0.638298 (-4311 2150);
PAINT MONO (-4311 2150);
FORCEPROP 2 LAST CDS_LIB standard
J 0
(-4500 2150);
DISPLAY INVISIBLE (-4500 2150);
FORCEPROP 1 LAST OFFPAGE TRUE
J 0
(-4175 2025);
DISPLAY 0.872340 (-4175 2025);
PAINT GREEN (-4175 2025);
DISPLAY INVISIBLE (-4175 2025);
FORCEPROP 1 LAST COMMENT_BODY TRUE
J 0
(-4545 2055);
DISPLAY 0.872340 (-4545 2055);
PAINT GREEN (-4545 2055);
DISPLAY INVISIBLE (-4545 2055);
FORCEPROP 2 LAST PATH I19
J 0
(-4325 2225);
DISPLAY 1.021277 (-4325 2225);
DISPLAY INVISIBLE (-4325 2225);
FORCEADD OFFPAGE..2
(-2300 5625);
FORCEPROP 2 LAST $XR1 81 
J 0
(-2021 5625);
DISPLAY 0.638298 (-2021 5625);
PAINT MONO (-2021 5625);
FORCEPROP 2 LAST $XR0 55 
J 0
(-2111 5625);
DISPLAY 0.638298 (-2111 5625);
PAINT MONO (-2111 5625);
FORCEPROP 2 LAST CDS_LIB standard
J 0
(-2300 5625);
DISPLAY INVISIBLE (-2300 5625);
FORCEPROP 1 LAST OFFPAGE TRUE
J 0
(-1975 5500);
DISPLAY 0.872340 (-1975 5500);
PAINT GREEN (-1975 5500);
DISPLAY INVISIBLE (-1975 5500);
FORCEPROP 1 LAST COMMENT_BODY TRUE
J 0
(-2345 5530);
DISPLAY 0.872340 (-2345 5530);
PAINT GREEN (-2345 5530);
DISPLAY INVISIBLE (-2345 5530);
FORCEPROP 2 LAST PATH I190
J 0
(-1900 5675);
DISPLAY 1.021277 (-1900 5675);
DISPLAY INVISIBLE (-1900 5675);
FORCEADD OFFPAGE..2
(-2300 5325);
FORCEPROP 2 LAST $XR1 81 
J 0
(-2021 5325);
DISPLAY 0.638298 (-2021 5325);
PAINT MONO (-2021 5325);
FORCEPROP 2 LAST $XR0 55 
J 0
(-2111 5325);
DISPLAY 0.638298 (-2111 5325);
PAINT MONO (-2111 5325);
FORCEPROP 2 LAST CDS_LIB standard
J 0
(-2300 5325);
DISPLAY INVISIBLE (-2300 5325);
FORCEPROP 1 LAST OFFPAGE TRUE
J 0
(-1975 5200);
DISPLAY 0.872340 (-1975 5200);
PAINT GREEN (-1975 5200);
DISPLAY INVISIBLE (-1975 5200);
FORCEPROP 1 LAST COMMENT_BODY TRUE
J 0
(-2345 5230);
DISPLAY 0.872340 (-2345 5230);
PAINT GREEN (-2345 5230);
DISPLAY INVISIBLE (-2345 5230);
FORCEPROP 2 LAST PATH I191
J 0
(-2000 5375);
DISPLAY 1.021277 (-2000 5375);
DISPLAY INVISIBLE (-2000 5375);
FORCEADD OFFPAGE..2
(-2275 5175);
FORCEPROP 2 LAST $XR1 83 
J 0
(-1996 5175);
DISPLAY 0.638298 (-1996 5175);
PAINT MONO (-1996 5175);
FORCEPROP 2 LAST $XR0 81 
J 0
(-2086 5175);
DISPLAY 0.638298 (-2086 5175);
PAINT MONO (-2086 5175);
FORCEPROP 2 LAST CDS_LIB standard
J 0
(-2275 5175);
DISPLAY INVISIBLE (-2275 5175);
FORCEPROP 1 LAST OFFPAGE TRUE
J 0
(-1950 5050);
DISPLAY 0.872340 (-1950 5050);
PAINT GREEN (-1950 5050);
DISPLAY INVISIBLE (-1950 5050);
FORCEPROP 1 LAST COMMENT_BODY TRUE
J 0
(-2320 5080);
DISPLAY 0.872340 (-2320 5080);
PAINT GREEN (-2320 5080);
DISPLAY INVISIBLE (-2320 5080);
FORCEPROP 2 LAST PATH I192
J 0
(-1975 5225);
DISPLAY 1.021277 (-1975 5225);
DISPLAY INVISIBLE (-1975 5225);
FORCEADD OFFPAGE..2
(-2275 5125);
FORCEPROP 2 LAST $XR1 83 
J 0
(-1996 5125);
DISPLAY 0.638298 (-1996 5125);
PAINT MONO (-1996 5125);
FORCEPROP 2 LAST $XR0 81 
J 0
(-2086 5125);
DISPLAY 0.638298 (-2086 5125);
PAINT MONO (-2086 5125);
FORCEPROP 2 LAST CDS_LIB standard
J 0
(-2275 5125);
DISPLAY INVISIBLE (-2275 5125);
FORCEPROP 1 LAST OFFPAGE TRUE
J 0
(-1950 5000);
DISPLAY 0.872340 (-1950 5000);
PAINT GREEN (-1950 5000);
DISPLAY INVISIBLE (-1950 5000);
FORCEPROP 1 LAST COMMENT_BODY TRUE
J 0
(-2320 5030);
DISPLAY 0.872340 (-2320 5030);
PAINT GREEN (-2320 5030);
DISPLAY INVISIBLE (-2320 5030);
FORCEPROP 2 LAST PATH I193
J 0
(-1975 5175);
DISPLAY 1.021277 (-1975 5175);
DISPLAY INVISIBLE (-1975 5175);
FORCEADD UNIVERSAL_GND..1
(-6175 525);
FORCEPROP 3 LASTPIN (-6175 575) SIG_NAME GND\g
J 0
(-6165 585);
DISPLAY 0.659574 (-6165 585);
PAINT MONO (-6165 585);
DISPLAY INVISIBLE (-6165 585);
FORCEPROP 2 LAST CDS_LIB pure_quanta_power
J 0
(-6175 525);
DISPLAY INVISIBLE (-6175 525);
FORCEPROP 1 LAST HDL_POWER GND
J 1
(-6150 450);
DISPLAY 0.872340 (-6150 450);
PAINT GREEN (-6150 450);
DISPLAY INVISIBLE (-6150 450);
FORCEPROP 1 LAST PATH I2
J 0
(-6100 525);
DISPLAY 0.872340 (-6100 525);
PAINT AQUA (-6100 525);
DISPLAY INVISIBLE (-6100 525);
FORCEADD OFFPAGE..1
(-7600 5525);
FORCEPROP 2 LAST $XR1 81 
J 0
(-7941 5525);
DISPLAY 0.638298 (-7941 5525);
PAINT MONO (-7941 5525);
FORCEPROP 2 LAST $XR0 55 
J 0
(-7851 5525);
DISPLAY 0.638298 (-7851 5525);
PAINT MONO (-7851 5525);
FORCEPROP 2 LAST CDS_LIB standard
J 0
(-7600 5525);
DISPLAY INVISIBLE (-7600 5525);
FORCEPROP 1 LAST OFFPAGE TRUE
J 0
(-7275 5400);
DISPLAY 0.872340 (-7275 5400);
PAINT GREEN (-7275 5400);
DISPLAY INVISIBLE (-7275 5400);
FORCEPROP 1 LAST COMMENT_BODY TRUE
J 0
(-7475 5425);
DISPLAY 0.872340 (-7475 5425);
PAINT GREEN (-7475 5425);
DISPLAY INVISIBLE (-7475 5425);
FORCEPROP 2 LAST PATH I212
J 0
(-7850 5575);
DISPLAY 1.021277 (-7850 5575);
DISPLAY INVISIBLE (-7850 5575);
FORCEADD OFFPAGE..1
(-6425 5425);
FORCEPROP 2 LAST $XR1 81 
J 0
(-6736 5425);
DISPLAY 0.638298 (-6736 5425);
PAINT MONO (-6736 5425);
FORCEPROP 2 LAST $XR0 28 
J 0
(-6646 5425);
DISPLAY 0.638298 (-6646 5425);
PAINT MONO (-6646 5425);
FORCEPROP 2 LAST CDS_LIB standard
J 0
(-6425 5425);
DISPLAY INVISIBLE (-6425 5425);
FORCEPROP 1 LAST OFFPAGE TRUE
J 0
(-6100 5300);
DISPLAY 0.872340 (-6100 5300);
PAINT GREEN (-6100 5300);
DISPLAY INVISIBLE (-6100 5300);
FORCEPROP 1 LAST COMMENT_BODY TRUE
J 0
(-6300 5325);
DISPLAY 0.872340 (-6300 5325);
PAINT GREEN (-6300 5325);
DISPLAY INVISIBLE (-6300 5325);
FORCEPROP 2 LAST PATH I215
J 0
(-6675 5475);
DISPLAY 1.021277 (-6675 5475);
DISPLAY INVISIBLE (-6675 5475);
FORCEADD OFFPAGE..1
(-6425 5575);
FORCEPROP 2 LAST $XR1 81 
J 0
(-6736 5575);
DISPLAY 0.638298 (-6736 5575);
PAINT MONO (-6736 5575);
FORCEPROP 2 LAST $XR0 55 
J 0
(-6646 5575);
DISPLAY 0.638298 (-6646 5575);
PAINT MONO (-6646 5575);
FORCEPROP 2 LAST CDS_LIB standard
J 0
(-6425 5575);
DISPLAY INVISIBLE (-6425 5575);
FORCEPROP 1 LAST OFFPAGE TRUE
J 0
(-6100 5450);
DISPLAY 0.872340 (-6100 5450);
PAINT GREEN (-6100 5450);
DISPLAY INVISIBLE (-6100 5450);
FORCEPROP 1 LAST COMMENT_BODY TRUE
J 0
(-6300 5475);
DISPLAY 0.872340 (-6300 5475);
PAINT GREEN (-6300 5475);
DISPLAY INVISIBLE (-6300 5475);
FORCEPROP 2 LAST PATH I216
J 0
(-6675 5625);
DISPLAY 1.021277 (-6675 5625);
DISPLAY INVISIBLE (-6675 5625);
FORCEADD OFFPAGE..1
(-6425 5225);
FORCEPROP 2 LAST $XR0 55 
J 0
(-6646 5225);
DISPLAY 0.638298 (-6646 5225);
PAINT MONO (-6646 5225);
FORCEPROP 2 LAST CDS_LIB standard
J 0
(-6425 5225);
DISPLAY INVISIBLE (-6425 5225);
FORCEPROP 1 LAST OFFPAGE TRUE
J 0
(-6100 5100);
DISPLAY 0.872340 (-6100 5100);
PAINT GREEN (-6100 5100);
DISPLAY INVISIBLE (-6100 5100);
FORCEPROP 1 LAST COMMENT_BODY TRUE
J 0
(-6300 5125);
DISPLAY 0.872340 (-6300 5125);
PAINT GREEN (-6300 5125);
DISPLAY INVISIBLE (-6300 5125);
FORCEPROP 2 LAST PATH I217
J 0
(-6675 5275);
DISPLAY 1.021277 (-6675 5275);
DISPLAY INVISIBLE (-6675 5275);
FORCEADD OFFPAGE..1
(-6425 5275);
FORCEPROP 2 LAST $XR0 55 
J 0
(-6646 5275);
DISPLAY 0.638298 (-6646 5275);
PAINT MONO (-6646 5275);
FORCEPROP 2 LAST CDS_LIB standard
J 0
(-6425 5275);
DISPLAY INVISIBLE (-6425 5275);
FORCEPROP 1 LAST OFFPAGE TRUE
J 0
(-6100 5150);
DISPLAY 0.872340 (-6100 5150);
PAINT GREEN (-6100 5150);
DISPLAY INVISIBLE (-6100 5150);
FORCEPROP 1 LAST COMMENT_BODY TRUE
J 0
(-6300 5175);
DISPLAY 0.872340 (-6300 5175);
PAINT GREEN (-6300 5175);
DISPLAY INVISIBLE (-6300 5175);
FORCEPROP 2 LAST PATH I218
J 0
(-6675 5325);
DISPLAY 1.021277 (-6675 5325);
DISPLAY INVISIBLE (-6675 5325);
FORCEADD OFFPAGE..1
(-6425 4675);
FORCEPROP 2 LAST $XR1 81 
J 0
(-6736 4675);
DISPLAY 0.638298 (-6736 4675);
PAINT MONO (-6736 4675);
FORCEPROP 2 LAST $XR0 55 
J 0
(-6646 4675);
DISPLAY 0.638298 (-6646 4675);
PAINT MONO (-6646 4675);
FORCEPROP 2 LAST CDS_LIB standard
J 0
(-6425 4675);
DISPLAY INVISIBLE (-6425 4675);
FORCEPROP 1 LAST OFFPAGE TRUE
J 0
(-6100 4550);
DISPLAY 0.872340 (-6100 4550);
PAINT GREEN (-6100 4550);
DISPLAY INVISIBLE (-6100 4550);
FORCEPROP 1 LAST COMMENT_BODY TRUE
J 0
(-6300 4575);
DISPLAY 0.872340 (-6300 4575);
PAINT GREEN (-6300 4575);
DISPLAY INVISIBLE (-6300 4575);
FORCEPROP 2 LAST PATH I219
J 0
(-6675 4725);
DISPLAY 1.021277 (-6675 4725);
DISPLAY INVISIBLE (-6675 4725);
FORCEADD OFFPAGE..1
(-6425 5025);
FORCEPROP 2 LAST $XR0 55 
J 0
(-6646 5025);
DISPLAY 0.638298 (-6646 5025);
PAINT MONO (-6646 5025);
FORCEPROP 2 LAST CDS_LIB standard
J 0
(-6425 5025);
DISPLAY INVISIBLE (-6425 5025);
FORCEPROP 1 LAST OFFPAGE TRUE
J 0
(-6100 4900);
DISPLAY 0.872340 (-6100 4900);
PAINT GREEN (-6100 4900);
DISPLAY INVISIBLE (-6100 4900);
FORCEPROP 1 LAST COMMENT_BODY TRUE
J 0
(-6300 4925);
DISPLAY 0.872340 (-6300 4925);
PAINT GREEN (-6300 4925);
DISPLAY INVISIBLE (-6300 4925);
FORCEPROP 2 LAST PATH I220
J 0
(-6675 5075);
DISPLAY 1.021277 (-6675 5075);
DISPLAY INVISIBLE (-6675 5075);
FORCEADD OFFPAGE..1
(-6425 5075);
FORCEPROP 2 LAST $XR0 55 
J 0
(-6646 5075);
DISPLAY 0.638298 (-6646 5075);
PAINT MONO (-6646 5075);
FORCEPROP 2 LAST CDS_LIB standard
J 0
(-6425 5075);
DISPLAY INVISIBLE (-6425 5075);
FORCEPROP 1 LAST OFFPAGE TRUE
J 0
(-6100 4950);
DISPLAY 0.872340 (-6100 4950);
PAINT GREEN (-6100 4950);
DISPLAY INVISIBLE (-6100 4950);
FORCEPROP 1 LAST COMMENT_BODY TRUE
J 0
(-6300 4975);
DISPLAY 0.872340 (-6300 4975);
PAINT GREEN (-6300 4975);
DISPLAY INVISIBLE (-6300 4975);
FORCEPROP 2 LAST PATH I221
J 0
(-6675 5125);
DISPLAY 1.021277 (-6675 5125);
DISPLAY INVISIBLE (-6675 5125);
FORCEADD OFFPAGE..2
R 2
(-6425 3725);
FORCEPROP 2 LAST $XR1 81 
J 0
(-6739 3725);
DISPLAY 0.638298 (-6739 3725);
PAINT MONO (-6739 3725);
FORCEPROP 2 LAST $XR0 55 
J 0
(-6649 3725);
DISPLAY 0.638298 (-6649 3725);
PAINT MONO (-6649 3725);
FORCEPROP 2 LAST CDS_LIB standard
J 0
(-6425 3725);
DISPLAY INVISIBLE (-6425 3725);
FORCEPROP 1 LAST OFFPAGE TRUE
J 2
(-6750 3600);
DISPLAY 0.872340 (-6750 3600);
PAINT GREEN (-6750 3600);
DISPLAY INVISIBLE (-6750 3600);
FORCEPROP 1 LAST COMMENT_BODY TRUE
J 2
(-6380 3630);
DISPLAY 0.872340 (-6380 3630);
PAINT GREEN (-6380 3630);
DISPLAY INVISIBLE (-6380 3630);
FORCEPROP 2 LAST PATH I230
J 0
(-6625 3775);
DISPLAY 1.021277 (-6625 3775);
DISPLAY INVISIBLE (-6625 3775);
FORCEADD Q_RES..1
(-6900 3475);
FORCEPROP 1 LAST LOCATION R570
J 0
(-7125 3475);
DISPLAY 0.489362 (-7125 3475);
PAINT SKYBLUE (-7125 3475);
FORCEPROP 0 LAST $SEC 1
J 0
(-7175 3525);
DISPLAY 0.680851 (-7175 3525);
PAINT MONO (-7175 3525);
DISPLAY INVISIBLE (-7175 3525);
FORCEPROP 0 LAST CDS_SEC 1
J 0
(-7175 3525);
DISPLAY 1.021277 (-7175 3525);
DISPLAY INVISIBLE (-7175 3525);
FORCEPROP 1 LASTPIN (-7000 3475) $PN 1
J 0
(-6988 3487);
DISPLAY 0.489362 (-6988 3487);
PAINT MONO (-6988 3487);
FORCEPROP 1 LASTPIN (-6800 3475) $PN 2
J 0
(-6838 3487);
DISPLAY 0.489362 (-6838 3487);
PAINT MONO (-6838 3487);
FORCEPROP 1 LAST VALUE 0
J 2
(-6750 3475);
DISPLAY 0.489362 (-6750 3475);
PAINT SKYBLUE (-6750 3475);
FORCEPROP 1 LAST PACK_TYPE 0402LF
J 0
(-6850 3400);
DISPLAY 0.489362 (-6850 3400);
PAINT SKYBLUE (-6850 3400);
DISPLAY INVISIBLE (-6850 3400);
FORCEPROP 1 LAST TOLERANCE 5%
J 0
(-6925 3400);
DISPLAY 0.489362 (-6925 3400);
PAINT SKYBLUE (-6925 3400);
DISPLAY INVISIBLE (-6925 3400);
FORCEPROP 1 LAST MATERIAL CHIP
J 0
(-6475 3400);
DISPLAY 0.489362 (-6475 3400);
PAINT SKYBLUE (-6475 3400);
DISPLAY INVISIBLE (-6475 3400);
FORCEPROP 1 LAST WATTAGE 1/16W
J 2
(-6500 3400);
DISPLAY 0.489362 (-6500 3400);
PAINT SKYBLUE (-6500 3400);
DISPLAY INVISIBLE (-6500 3400);
FORCEPROP 2 LAST CDS_LIB pure_quanta
J 0
(-6900 3475);
DISPLAY INVISIBLE (-6900 3475);
FORCEPROP 1 LAST PATH I236
J 0
(-6950 3625);
DISPLAY 0.978723 (-6950 3625);
PAINT WHITE (-6950 3625);
DISPLAY INVISIBLE (-6950 3625);
FORCEPROP 1 LAST PART_NUMBER CS00002JB13
J 0
(-6875 3525);
DISPLAY 0.489362 (-6875 3525);
PAINT SKYBLUE (-6875 3525);
DISPLAY INVISIBLE (-6875 3525);
FORCEADD Q_RES..1
(-2250 2175);
FORCEPROP 1 LAST LOCATION R574
J 0
(-2575 2175);
DISPLAY 0.489362 (-2575 2175);
PAINT SKYBLUE (-2575 2175);
FORCEPROP 0 LAST $SEC 1
J 0
(-2425 2350);
DISPLAY 0.680851 (-2425 2350);
PAINT MONO (-2425 2350);
DISPLAY INVISIBLE (-2425 2350);
FORCEPROP 0 LAST CDS_SEC 1
J 0
(-2425 2350);
DISPLAY 1.021277 (-2425 2350);
DISPLAY INVISIBLE (-2425 2350);
FORCEPROP 1 LASTPIN (-2350 2175) $PN 1
J 0
(-2338 2187);
DISPLAY 0.489362 (-2338 2187);
PAINT MONO (-2338 2187);
FORCEPROP 1 LASTPIN (-2150 2175) $PN 2
J 0
(-2188 2187);
DISPLAY 0.489362 (-2188 2187);
PAINT MONO (-2188 2187);
FORCEPROP 1 LAST VALUE 0
J 2
(-2050 2175);
DISPLAY 0.489362 (-2050 2175);
PAINT SKYBLUE (-2050 2175);
FORCEPROP 1 LAST MATERIAL EMPTY
J 0
(-2450 2175);
DISPLAY 0.489362 (-2450 2175);
PAINT RED (-2450 2175);
FORCEPROP 1 LAST PACK_TYPE 0402LF
J 0
(-1800 2250);
DISPLAY 0.489362 (-1800 2250);
PAINT SKYBLUE (-1800 2250);
DISPLAY INVISIBLE (-1800 2250);
FORCEPROP 1 LAST TOLERANCE 5%
J 0
(-2425 2250);
DISPLAY 0.489362 (-2425 2250);
PAINT SKYBLUE (-2425 2250);
DISPLAY INVISIBLE (-2425 2250);
FORCEPROP 1 LAST WATTAGE 1/16W
J 2
(-2075 2250);
DISPLAY 0.489362 (-2075 2250);
PAINT SKYBLUE (-2075 2250);
DISPLAY INVISIBLE (-2075 2250);
FORCEPROP 2 LAST CDS_LIB pure_quanta
J 0
(-2250 2175);
DISPLAY INVISIBLE (-2250 2175);
FORCEPROP 1 LAST PATH I24
J 0
(-2300 2325);
DISPLAY 0.978723 (-2300 2325);
PAINT WHITE (-2300 2325);
DISPLAY INVISIBLE (-2300 2325);
FORCEPROP 1 LAST PART_NUMBER CS00002JB13
J 0
(-2425 2300);
DISPLAY 0.489362 (-2425 2300);
PAINT SKYBLUE (-2425 2300);
DISPLAY INVISIBLE (-2425 2300);
FORCEADD OFFPAGE..2
R 2
(-7900 3475);
FORCEPROP 2 LAST $XR1 81 
J 0
(-8214 3475);
DISPLAY 0.638298 (-8214 3475);
PAINT MONO (-8214 3475);
FORCEPROP 2 LAST $XR0 55 
J 0
(-8124 3475);
DISPLAY 0.638298 (-8124 3475);
PAINT MONO (-8124 3475);
FORCEPROP 2 LAST CDS_LIB standard
J 2
(-7900 3475);
DISPLAY INVISIBLE (-7900 3475);
FORCEPROP 1 LAST OFFPAGE TRUE
J 2
(-8225 3350);
DISPLAY 0.872340 (-8225 3350);
PAINT GREEN (-8225 3350);
DISPLAY INVISIBLE (-8225 3350);
FORCEPROP 1 LAST COMMENT_BODY TRUE
J 2
(-7855 3380);
DISPLAY 0.872340 (-7855 3380);
PAINT GREEN (-7855 3380);
DISPLAY INVISIBLE (-7855 3380);
FORCEPROP 2 LAST PATH I241
J 0
(-8150 3525);
DISPLAY 1.021277 (-8150 3525);
DISPLAY INVISIBLE (-8150 3525);
FORCEADD OFFPAGE..2
R 2
(-6850 4425);
FORCEPROP 2 LAST $XR1 159 
J 0
(-7224 4425);
DISPLAY 0.638298 (-7224 4425);
PAINT MONO (-7224 4425);
FORCEPROP 2 LAST $XR0 55 
J 0
(-7104 4425);
DISPLAY 0.638298 (-7104 4425);
PAINT MONO (-7104 4425);
FORCEPROP 2 LAST CDS_LIB standard
J 2
(-6850 4425);
DISPLAY INVISIBLE (-6850 4425);
FORCEPROP 1 LAST OFFPAGE TRUE
J 2
(-7175 4300);
DISPLAY 0.872340 (-7175 4300);
PAINT GREEN (-7175 4300);
DISPLAY INVISIBLE (-7175 4300);
FORCEPROP 1 LAST COMMENT_BODY TRUE
J 2
(-6805 4330);
DISPLAY 0.872340 (-6805 4330);
PAINT GREEN (-6805 4330);
DISPLAY INVISIBLE (-6805 4330);
FORCEPROP 2 LAST PATH I251
J 0
(-7100 4475);
DISPLAY 1.021277 (-7100 4475);
DISPLAY INVISIBLE (-7100 4475);
FORCEADD OFFPAGE..3
R 2
(-6850 4375);
FORCEPROP 2 LAST $XR1 159 
J 0
(-7219 4375);
DISPLAY 0.638298 (-7219 4375);
PAINT MONO (-7219 4375);
FORCEPROP 2 LAST $XR0 55 
J 0
(-7099 4375);
DISPLAY 0.638298 (-7099 4375);
PAINT MONO (-7099 4375);
FORCEPROP 2 LAST CDS_LIB standard
J 0
(-6850 4375);
DISPLAY INVISIBLE (-6850 4375);
FORCEPROP 1 LAST OFFPAGE TRUE
J 2
(-7175 4250);
DISPLAY 0.872340 (-7175 4250);
PAINT GREEN (-7175 4250);
DISPLAY INVISIBLE (-7175 4250);
FORCEPROP 1 LAST COMMENT_BODY TRUE
J 2
(-6800 4275);
DISPLAY 0.872340 (-6800 4275);
PAINT PEACH (-6800 4275);
DISPLAY INVISIBLE (-6800 4275);
FORCEPROP 2 LAST PATH I252
J 0
(-7125 4425);
DISPLAY 1.021277 (-7125 4425);
DISPLAY INVISIBLE (-7125 4425);
FORCEADD OFFPAGE..2
R 2
(-6850 4325);
FORCEPROP 2 LAST $XR1 159 
J 0
(-7224 4325);
DISPLAY 0.638298 (-7224 4325);
PAINT MONO (-7224 4325);
FORCEPROP 2 LAST $XR0 55 
J 0
(-7104 4325);
DISPLAY 0.638298 (-7104 4325);
PAINT MONO (-7104 4325);
FORCEPROP 2 LAST CDS_LIB standard
J 2
(-6850 4325);
DISPLAY INVISIBLE (-6850 4325);
FORCEPROP 1 LAST OFFPAGE TRUE
J 2
(-7175 4200);
DISPLAY 0.872340 (-7175 4200);
PAINT GREEN (-7175 4200);
DISPLAY INVISIBLE (-7175 4200);
FORCEPROP 1 LAST COMMENT_BODY TRUE
J 2
(-6805 4230);
DISPLAY 0.872340 (-6805 4230);
PAINT GREEN (-6805 4230);
DISPLAY INVISIBLE (-6805 4230);
FORCEPROP 2 LAST PATH I253
J 0
(-7100 4375);
DISPLAY 1.021277 (-7100 4375);
DISPLAY INVISIBLE (-7100 4375);
FORCEADD OFFPAGE..3
R 2
(-6850 4275);
FORCEPROP 2 LAST $XR1 159 
J 0
(-7219 4275);
DISPLAY 0.638298 (-7219 4275);
PAINT MONO (-7219 4275);
FORCEPROP 2 LAST $XR0 55 
J 0
(-7099 4275);
DISPLAY 0.638298 (-7099 4275);
PAINT MONO (-7099 4275);
FORCEPROP 2 LAST CDS_LIB standard
J 0
(-6850 4275);
DISPLAY INVISIBLE (-6850 4275);
FORCEPROP 1 LAST OFFPAGE TRUE
J 2
(-7175 4150);
DISPLAY 0.872340 (-7175 4150);
PAINT GREEN (-7175 4150);
DISPLAY INVISIBLE (-7175 4150);
FORCEPROP 1 LAST COMMENT_BODY TRUE
J 2
(-6800 4175);
DISPLAY 0.872340 (-6800 4175);
PAINT PEACH (-6800 4175);
DISPLAY INVISIBLE (-6800 4175);
FORCEPROP 2 LAST PATH I254
J 0
(-7125 4325);
DISPLAY 1.021277 (-7125 4325);
DISPLAY INVISIBLE (-7125 4325);
FORCEADD OFFPAGE..3
(-2150 3125);
FORCEPROP 2 LAST $XR0 161 
J 0
(-1936 3125);
DISPLAY 0.638298 (-1936 3125);
PAINT MONO (-1936 3125);
FORCEPROP 2 LAST CDS_LIB standard
J 0
(-2150 3125);
DISPLAY INVISIBLE (-2150 3125);
FORCEPROP 1 LAST OFFPAGE TRUE
J 0
(-1825 3000);
DISPLAY 0.872340 (-1825 3000);
PAINT GREEN (-1825 3000);
DISPLAY INVISIBLE (-1825 3000);
FORCEPROP 1 LAST COMMENT_BODY TRUE
J 0
(-2200 3025);
DISPLAY 0.872340 (-2200 3025);
PAINT PEACH (-2200 3025);
DISPLAY INVISIBLE (-2200 3025);
FORCEPROP 2 LAST PATH I255
J 0
(-1950 3200);
DISPLAY 1.021277 (-1950 3200);
DISPLAY INVISIBLE (-1950 3200);
FORCEADD OFFPAGE..1
R 2
(-2150 3175);
FORCEPROP 2 LAST $XR0 161 
J 0
(-1964 3175);
DISPLAY 0.638298 (-1964 3175);
PAINT MONO (-1964 3175);
FORCEPROP 2 LAST CDS_LIB standard
J 0
(-2150 3175);
DISPLAY INVISIBLE (-2150 3175);
FORCEPROP 1 LAST OFFPAGE TRUE
J 2
(-2475 3050);
DISPLAY 0.872340 (-2475 3050);
PAINT GREEN (-2475 3050);
DISPLAY INVISIBLE (-2475 3050);
FORCEPROP 1 LAST COMMENT_BODY TRUE
J 2
(-2275 3075);
DISPLAY 0.872340 (-2275 3075);
PAINT GREEN (-2275 3075);
DISPLAY INVISIBLE (-2275 3075);
FORCEPROP 2 LAST PATH I256
J 0
(-1975 3250);
DISPLAY 1.021277 (-1975 3250);
DISPLAY INVISIBLE (-1975 3250);
FORCEADD Q_RES..1
(-2250 2425);
FORCEPROP 1 LAST LOCATION R573
J 0
(-2425 2425);
DISPLAY 0.489362 (-2425 2425);
PAINT SKYBLUE (-2425 2425);
FORCEPROP 0 LAST $SEC 1
J 0
(-1975 2475);
DISPLAY 0.680851 (-1975 2475);
PAINT MONO (-1975 2475);
DISPLAY INVISIBLE (-1975 2475);
FORCEPROP 0 LAST CDS_SEC 1
J 0
(-1975 2475);
DISPLAY 1.021277 (-1975 2475);
DISPLAY INVISIBLE (-1975 2475);
FORCEPROP 1 LASTPIN (-2350 2425) $PN 1
J 0
(-2338 2437);
DISPLAY 0.489362 (-2338 2437);
PAINT MONO (-2338 2437);
FORCEPROP 1 LASTPIN (-2150 2425) $PN 2
J 0
(-2188 2437);
DISPLAY 0.489362 (-2188 2437);
PAINT MONO (-2188 2437);
FORCEPROP 1 LAST VALUE 0
J 2
(-2050 2425);
DISPLAY 0.489362 (-2050 2425);
PAINT SKYBLUE (-2050 2425);
FORCEPROP 1 LAST MATERIAL CHIP
J 0
(-2425 2400);
DISPLAY 0.489362 (-2425 2400);
PAINT SKYBLUE (-2425 2400);
FORCEPROP 1 LAST PACK_TYPE 0402LF
J 0
(-2000 2275);
DISPLAY 0.978723 (-2000 2275);
PAINT SKYBLUE (-2000 2275);
DISPLAY INVISIBLE (-2000 2275);
FORCEPROP 1 LAST TOLERANCE 5%
J 0
(-2250 2325);
DISPLAY 0.978723 (-2250 2325);
PAINT SKYBLUE (-2250 2325);
DISPLAY INVISIBLE (-2250 2325);
FORCEPROP 1 LAST WATTAGE 1/16W
J 2
(-2275 2275);
DISPLAY 0.978723 (-2275 2275);
PAINT SKYBLUE (-2275 2275);
DISPLAY INVISIBLE (-2275 2275);
FORCEPROP 2 LAST CDS_LIB pure_quanta
J 0
(-2250 2425);
DISPLAY INVISIBLE (-2250 2425);
FORCEPROP 1 LAST PATH I26
J 0
(-2300 2575);
DISPLAY 0.978723 (-2300 2575);
PAINT WHITE (-2300 2575);
DISPLAY INVISIBLE (-2300 2575);
FORCEPROP 1 LAST PART_NUMBER CS00002JB13
J 0
(-2300 2550);
DISPLAY 0.978723 (-2300 2550);
PAINT SKYBLUE (-2300 2550);
DISPLAY INVISIBLE (-2300 2550);
FORCEADD OFFPAGE..1
(-3125 2425);
FORCEPROP 2 LAST $XR1 76 
J 0
(-3436 2425);
DISPLAY 0.638298 (-3436 2425);
PAINT MONO (-3436 2425);
FORCEPROP 2 LAST $XR0 28 
J 0
(-3346 2425);
DISPLAY 0.638298 (-3346 2425);
PAINT MONO (-3346 2425);
FORCEPROP 2 LAST CDS_LIB standard
J 0
(-3125 2425);
DISPLAY INVISIBLE (-3125 2425);
FORCEPROP 1 LAST OFFPAGE TRUE
J 0
(-2800 2300);
DISPLAY 0.872340 (-2800 2300);
PAINT GREEN (-2800 2300);
DISPLAY INVISIBLE (-2800 2300);
FORCEPROP 1 LAST COMMENT_BODY TRUE
J 0
(-3000 2325);
DISPLAY 0.872340 (-3000 2325);
PAINT GREEN (-3000 2325);
DISPLAY INVISIBLE (-3000 2325);
FORCEPROP 2 LAST PATH I27
J 0
(-3075 2500);
DISPLAY 1.021277 (-3075 2500);
DISPLAY INVISIBLE (-3075 2500);
FORCEADD OFFPAGE..2
(-675 4175);
FORCEPROP 2 LAST $XR0 122 
J 0
(-486 4175);
DISPLAY 0.638298 (-486 4175);
PAINT MONO (-486 4175);
FORCEPROP 2 LAST CDS_LIB standard
J 0
(-675 4175);
DISPLAY INVISIBLE (-675 4175);
FORCEPROP 1 LAST OFFPAGE TRUE
J 0
(-350 4050);
DISPLAY 0.872340 (-350 4050);
PAINT GREEN (-350 4050);
DISPLAY INVISIBLE (-350 4050);
FORCEPROP 1 LAST COMMENT_BODY TRUE
J 0
(-720 4080);
DISPLAY 0.872340 (-720 4080);
PAINT GREEN (-720 4080);
DISPLAY INVISIBLE (-720 4080);
FORCEPROP 2 LAST PATH I277
J 0
(-475 4225);
DISPLAY 0.680851 (-475 4225);
DISPLAY INVISIBLE (-475 4225);
FORCEADD OFFPAGE..2
(-675 4125);
FORCEPROP 2 LAST $XR0 122 
J 0
(-486 4125);
DISPLAY 0.638298 (-486 4125);
PAINT MONO (-486 4125);
FORCEPROP 2 LAST CDS_LIB standard
J 0
(-675 4125);
DISPLAY INVISIBLE (-675 4125);
FORCEPROP 1 LAST OFFPAGE TRUE
J 0
(-350 4000);
DISPLAY 0.872340 (-350 4000);
PAINT GREEN (-350 4000);
DISPLAY INVISIBLE (-350 4000);
FORCEPROP 1 LAST COMMENT_BODY TRUE
J 0
(-720 4030);
DISPLAY 0.872340 (-720 4030);
PAINT GREEN (-720 4030);
DISPLAY INVISIBLE (-720 4030);
FORCEPROP 2 LAST PATH I278
J 0
(-475 4175);
DISPLAY 0.680851 (-475 4175);
DISPLAY INVISIBLE (-475 4175);
FORCEADD UNIVERSAL_POWER..1
R 2
(-7375 4975);
FORCEPROP 3 LASTPIN (-7375 4925) SIG_NAME PVDD18_S5_P1\g
J 0
(-7365 4935);
DISPLAY 0.659574 (-7365 4935);
PAINT MONO (-7365 4935);
DISPLAY INVISIBLE (-7365 4935);
FORCEPROP 1 LAST HDL_POWER PVDD18_S5_P1
J 1
(-7350 5025);
DISPLAY 0.489362 (-7350 5025);
PAINT GREEN (-7350 5025);
FORCEPROP 2 LAST CDS_LIB pure_quanta_power
J 0
(-7375 4975);
DISPLAY INVISIBLE (-7375 4975);
FORCEPROP 1 LAST PATH I291
J 2
(-7425 5000);
DISPLAY 0.872340 (-7425 5000);
PAINT AQUA (-7425 5000);
DISPLAY INVISIBLE (-7425 5000);
FORCEADD Q_RES..1
(-7050 4875);
FORCEPROP 1 LAST LOCATION R1424
J 2
(-6900 4875);
DISPLAY 0.489362 (-6900 4875);
PAINT SKYBLUE (-6900 4875);
FORCEPROP 0 LAST $SEC 1
J 0
(-6900 4900);
DISPLAY 0.680851 (-6900 4900);
PAINT MONO (-6900 4900);
DISPLAY INVISIBLE (-6900 4900);
FORCEPROP 0 LAST CDS_SEC 1
J 0
(-6900 4900);
DISPLAY 0.680851 (-6900 4900);
DISPLAY INVISIBLE (-6900 4900);
FORCEPROP 1 LASTPIN (-7150 4875) $PN 1
J 0
(-7138 4887);
DISPLAY 0.489362 (-7138 4887);
PAINT MONO (-7138 4887);
FORCEPROP 1 LASTPIN (-6950 4875) $PN 2
J 0
(-6988 4887);
DISPLAY 0.489362 (-6988 4887);
PAINT MONO (-6988 4887);
FORCEPROP 1 LAST VALUE 2.2K
J 0
(-7300 4875);
DISPLAY 0.489362 (-7300 4875);
PAINT SKYBLUE (-7300 4875);
FORCEPROP 2 LAST CDS_LIB pure_quanta
J 0
(-7050 4875);
DISPLAY INVISIBLE (-7050 4875);
FORCEPROP 1 LAST WATTAGE 1/16W
J 2
(-7075 4725);
DISPLAY 0.978723 (-7075 4725);
PAINT SKYBLUE (-7075 4725);
DISPLAY INVISIBLE (-7075 4725);
FORCEPROP 1 LAST MATERIAL CHIP
J 0
(-7050 4725);
DISPLAY 0.978723 (-7050 4725);
PAINT SKYBLUE (-7050 4725);
DISPLAY INVISIBLE (-7050 4725);
FORCEPROP 1 LAST TOLERANCE 5%
J 0
(-7050 4775);
DISPLAY 0.978723 (-7050 4775);
PAINT SKYBLUE (-7050 4775);
DISPLAY INVISIBLE (-7050 4775);
FORCEPROP 1 LAST PACK_TYPE 0402LF
J 0
(-6800 4725);
DISPLAY 0.978723 (-6800 4725);
PAINT SKYBLUE (-6800 4725);
DISPLAY INVISIBLE (-6800 4725);
FORCEPROP 1 LAST PATH I292
J 0
(-7100 5025);
DISPLAY 0.978723 (-7100 5025);
PAINT WHITE (-7100 5025);
DISPLAY INVISIBLE (-7100 5025);
FORCEPROP 1 LAST PART_NUMBER CS22202JB07
J 0
(-7100 4975);
DISPLAY 0.978723 (-7100 4975);
PAINT SKYBLUE (-7100 4975);
DISPLAY INVISIBLE (-7100 4975);
FORCEADD Q_RES..1
(-2250 2125);
FORCEPROP 1 LAST LOCATION R575
J 0
(-2575 2125);
DISPLAY 0.489362 (-2575 2125);
PAINT SKYBLUE (-2575 2125);
FORCEPROP 0 LAST $SEC 1
J 0
(-2050 2150);
DISPLAY 0.680851 (-2050 2150);
PAINT MONO (-2050 2150);
DISPLAY INVISIBLE (-2050 2150);
FORCEPROP 0 LAST CDS_SEC 1
J 0
(-2050 2150);
DISPLAY 0.680851 (-2050 2150);
DISPLAY INVISIBLE (-2050 2150);
FORCEPROP 1 LASTPIN (-2350 2125) $PN 1
J 0
(-2338 2137);
DISPLAY 0.489362 (-2338 2137);
PAINT MONO (-2338 2137);
FORCEPROP 1 LASTPIN (-2150 2125) $PN 2
J 0
(-2188 2137);
DISPLAY 0.489362 (-2188 2137);
PAINT MONO (-2188 2137);
FORCEPROP 1 LAST VALUE 0
J 2
(-2050 2125);
DISPLAY 0.489362 (-2050 2125);
PAINT SKYBLUE (-2050 2125);
FORCEPROP 1 LAST MATERIAL EMPTY
J 0
(-2450 2125);
DISPLAY 0.489362 (-2450 2125);
PAINT RED (-2450 2125);
FORCEPROP 1 LAST PACK_TYPE 0402LF
J 0
(-1800 2200);
DISPLAY 0.489362 (-1800 2200);
PAINT SKYBLUE (-1800 2200);
DISPLAY INVISIBLE (-1800 2200);
FORCEPROP 1 LAST TOLERANCE 5%
J 0
(-2425 2200);
DISPLAY 0.489362 (-2425 2200);
PAINT SKYBLUE (-2425 2200);
DISPLAY INVISIBLE (-2425 2200);
FORCEPROP 1 LAST WATTAGE 1/16W
J 2
(-2075 2200);
DISPLAY 0.489362 (-2075 2200);
PAINT SKYBLUE (-2075 2200);
DISPLAY INVISIBLE (-2075 2200);
FORCEPROP 2 LAST CDS_LIB pure_quanta
J 0
(-2250 2125);
DISPLAY INVISIBLE (-2250 2125);
FORCEPROP 1 LAST PATH I296
J 0
(-2300 2275);
DISPLAY 0.978723 (-2300 2275);
PAINT WHITE (-2300 2275);
DISPLAY INVISIBLE (-2300 2275);
FORCEPROP 1 LAST PART_NUMBER CS00002JB13
J 0
(-2425 2250);
DISPLAY 0.489362 (-2425 2250);
PAINT SKYBLUE (-2425 2250);
DISPLAY INVISIBLE (-2425 2250);
FORCEADD Q_RES..1
(-6625 5775);
FORCEPROP 1 LAST LOCATION R191
J 0
(-6500 5775);
DISPLAY 0.489362 (-6500 5775);
PAINT SKYBLUE (-6500 5775);
FORCEPROP 0 LAST $SEC 1
J 2
(-6500 5825);
DISPLAY 0.680851 (-6500 5825);
PAINT MONO (-6500 5825);
DISPLAY INVISIBLE (-6500 5825);
FORCEPROP 0 LAST CDS_SEC 1
J 2
(-6500 5825);
DISPLAY 1.021277 (-6500 5825);
DISPLAY INVISIBLE (-6500 5825);
FORCEPROP 1 LASTPIN (-6725 5775) $PN 1
J 0
(-6713 5787);
DISPLAY 0.489362 (-6713 5787);
PAINT MONO (-6713 5787);
FORCEPROP 1 LASTPIN (-6525 5775) $PN 2
J 0
(-6563 5787);
DISPLAY 0.489362 (-6563 5787);
PAINT MONO (-6563 5787);
FORCEPROP 1 LAST MATERIAL EMPTY
J 2
(-6800 5775);
DISPLAY 0.489362 (-6800 5775);
PAINT RED (-6800 5775);
FORCEPROP 1 LAST VALUE 0
J 2
(-6750 5775);
DISPLAY 0.489362 (-6750 5775);
PAINT SKYBLUE (-6750 5775);
FORCEPROP 2 LAST BOM_COST MEM
J 2
(-6600 5925);
DISPLAY 0.744681 (-6600 5925);
PAINT WHITE (-6600 5925);
DISPLAY INVISIBLE (-6600 5925);
FORCEPROP 2 LAST CDS_LIB pure_quanta
J 2
(-6625 5775);
DISPLAY INVISIBLE (-6625 5775);
FORCEPROP 1 LAST WATTAGE 1/16W
J 2
(-6700 5700);
DISPLAY 0.489362 (-6700 5700);
PAINT SKYBLUE (-6700 5700);
DISPLAY INVISIBLE (-6700 5700);
FORCEPROP 1 LAST TOLERANCE 5%
J 0
(-6750 5750);
DISPLAY 0.489362 (-6750 5750);
PAINT SKYBLUE (-6750 5750);
DISPLAY INVISIBLE (-6750 5750);
FORCEPROP 1 LAST PACK_TYPE 0402LF
J 2
(-6450 5700);
DISPLAY 0.489362 (-6450 5700);
PAINT SKYBLUE (-6450 5700);
DISPLAY INVISIBLE (-6450 5700);
FORCEPROP 1 LAST PATH I297
J 0
(-6675 5925);
DISPLAY 0.978723 (-6675 5925);
PAINT WHITE (-6675 5925);
DISPLAY INVISIBLE (-6675 5925);
FORCEPROP 1 LAST PART_NUMBER CS00002JB13
J 2
(-6525 5825);
DISPLAY 0.489362 (-6525 5825);
PAINT SKYBLUE (-6525 5825);
DISPLAY INVISIBLE (-6525 5825);
FORCEADD Q_RES..1
(-6625 5725);
FORCEPROP 1 LAST LOCATION R192
J 0
(-6500 5725);
DISPLAY 0.489362 (-6500 5725);
PAINT SKYBLUE (-6500 5725);
FORCEPROP 0 LAST $SEC 1
J 2
(-6500 5775);
DISPLAY 0.680851 (-6500 5775);
PAINT MONO (-6500 5775);
DISPLAY INVISIBLE (-6500 5775);
FORCEPROP 0 LAST CDS_SEC 1
J 2
(-6500 5775);
DISPLAY 1.021277 (-6500 5775);
DISPLAY INVISIBLE (-6500 5775);
FORCEPROP 1 LASTPIN (-6725 5725) $PN 1
J 0
(-6713 5737);
DISPLAY 0.489362 (-6713 5737);
PAINT MONO (-6713 5737);
FORCEPROP 1 LASTPIN (-6525 5725) $PN 2
J 0
(-6563 5737);
DISPLAY 0.489362 (-6563 5737);
PAINT MONO (-6563 5737);
FORCEPROP 1 LAST MATERIAL EMPTY
J 2
(-6800 5725);
DISPLAY 0.489362 (-6800 5725);
PAINT RED (-6800 5725);
FORCEPROP 1 LAST VALUE 0
J 2
(-6750 5725);
DISPLAY 0.489362 (-6750 5725);
PAINT SKYBLUE (-6750 5725);
FORCEPROP 2 LAST BOM_COST MEM
J 2
(-6600 5875);
DISPLAY 0.744681 (-6600 5875);
PAINT WHITE (-6600 5875);
DISPLAY INVISIBLE (-6600 5875);
FORCEPROP 2 LAST CDS_LIB pure_quanta
J 2
(-6625 5725);
DISPLAY INVISIBLE (-6625 5725);
FORCEPROP 1 LAST WATTAGE 1/16W
J 2
(-6700 5650);
DISPLAY 0.489362 (-6700 5650);
PAINT SKYBLUE (-6700 5650);
DISPLAY INVISIBLE (-6700 5650);
FORCEPROP 1 LAST TOLERANCE 5%
J 0
(-6750 5700);
DISPLAY 0.489362 (-6750 5700);
PAINT SKYBLUE (-6750 5700);
DISPLAY INVISIBLE (-6750 5700);
FORCEPROP 1 LAST PACK_TYPE 0402LF
J 2
(-6450 5650);
DISPLAY 0.489362 (-6450 5650);
PAINT SKYBLUE (-6450 5650);
DISPLAY INVISIBLE (-6450 5650);
FORCEPROP 1 LAST PATH I298
J 0
(-6675 5875);
DISPLAY 0.978723 (-6675 5875);
PAINT WHITE (-6675 5875);
DISPLAY INVISIBLE (-6675 5875);
FORCEPROP 1 LAST PART_NUMBER CS00002JB13
J 2
(-6525 5775);
DISPLAY 0.489362 (-6525 5775);
PAINT SKYBLUE (-6525 5775);
DISPLAY INVISIBLE (-6525 5775);
FORCEADD OFFPAGE..2
R 2
(-7625 5775);
FORCEPROP 2 LAST $XR0 81 
J 0
(-7879 5775);
DISPLAY 0.638298 (-7879 5775);
PAINT MONO (-7879 5775);
FORCEPROP 2 LAST CDS_LIB standard
J 0
(-7625 5775);
DISPLAY INVISIBLE (-7625 5775);
FORCEPROP 1 LAST OFFPAGE TRUE
J 2
(-7950 5650);
DISPLAY 0.872340 (-7950 5650);
PAINT GREEN (-7950 5650);
DISPLAY INVISIBLE (-7950 5650);
FORCEPROP 1 LAST COMMENT_BODY TRUE
J 2
(-7580 5680);
DISPLAY 0.872340 (-7580 5680);
PAINT GREEN (-7580 5680);
DISPLAY INVISIBLE (-7580 5680);
FORCEPROP 2 LAST PATH I299
J 0
(-7825 5825);
DISPLAY 0.680851 (-7825 5825);
DISPLAY INVISIBLE (-7825 5825);
FORCEADD Q_CAP..1
(-6175 825);
FORCEPROP 1 LAST LOCATION C236
J 0
(-6125 925);
DISPLAY 0.489362 (-6125 925);
PAINT SKYBLUE (-6125 925);
FORCEPROP 0 LAST $SEC 1
J 0
(-6125 975);
DISPLAY 0.680851 (-6125 975);
PAINT MONO (-6125 975);
DISPLAY INVISIBLE (-6125 975);
FORCEPROP 0 LAST CDS_SEC 1
J 0
(-6125 975);
DISPLAY 1.021277 (-6125 975);
DISPLAY INVISIBLE (-6125 975);
FORCEPROP 1 LASTPIN (-6175 925) $PN 1
J 0
(-6165 905);
DISPLAY 0.489362 (-6165 905);
PAINT MONO (-6165 905);
FORCEPROP 1 LASTPIN (-6175 725) $PN 2
J 0
(-6165 705);
DISPLAY 0.489362 (-6165 705);
PAINT MONO (-6165 705);
FORCEPROP 1 LAST PACK_TYPE C0402
J 0
(-6125 625);
DISPLAY 0.489362 (-6125 625);
PAINT SKYBLUE (-6125 625);
FORCEPROP 1 LAST TOLERANCE 0.1PF
J 0
(-6125 775);
DISPLAY 0.489362 (-6125 775);
PAINT SKYBLUE (-6125 775);
FORCEPROP 1 LAST VOLTAGE 50V
J 0
(-6125 825);
DISPLAY 0.489362 (-6125 825);
PAINT SKYBLUE (-6125 825);
FORCEPROP 1 LAST MATERIAL NPO
J 0
(-6125 725);
DISPLAY 0.489362 (-6125 725);
PAINT SKYBLUE (-6125 725);
FORCEPROP 1 LAST VALUE 2.7PF
J 0
(-6125 875);
DISPLAY 0.489362 (-6125 875);
PAINT SKYBLUE (-6125 875);
FORCEPROP 2 LAST CDS_LIB pure_quanta
J 0
(-6175 825);
DISPLAY INVISIBLE (-6175 825);
FORCEPROP 1 LAST PATH I3
J 0
(-6125 975);
DISPLAY 0.978723 (-6125 975);
PAINT WHITE (-6125 975);
DISPLAY INVISIBLE (-6125 975);
FORCEPROP 1 LAST PART_NUMBER CH-276B0B00
J 0
(-6125 675);
DISPLAY 0.489362 (-6125 675);
PAINT SKYBLUE (-6125 675);
DISPLAY INVISIBLE (-6125 675);
FORCEADD OFFPAGE..2
R 2
(-7625 5725);
FORCEPROP 2 LAST $XR0 81 
J 0
(-7879 5725);
DISPLAY 0.638298 (-7879 5725);
PAINT MONO (-7879 5725);
FORCEPROP 2 LAST CDS_LIB standard
J 0
(-7625 5725);
DISPLAY INVISIBLE (-7625 5725);
FORCEPROP 1 LAST OFFPAGE TRUE
J 2
(-7950 5600);
DISPLAY 0.872340 (-7950 5600);
PAINT GREEN (-7950 5600);
DISPLAY INVISIBLE (-7950 5600);
FORCEPROP 1 LAST COMMENT_BODY TRUE
J 2
(-7580 5630);
DISPLAY 0.872340 (-7580 5630);
PAINT GREEN (-7580 5630);
DISPLAY INVISIBLE (-7580 5630);
FORCEPROP 2 LAST PATH I300
J 0
(-7825 5775);
DISPLAY 0.680851 (-7825 5775);
DISPLAY INVISIBLE (-7825 5775);
FORCEADD OFFPAGE..2
(-2175 5975);
FORCEPROP 2 LAST $XR0 76 
J 0
(-1986 5975);
DISPLAY 0.638298 (-1986 5975);
PAINT MONO (-1986 5975);
FORCEPROP 2 LAST CDS_LIB standard
J 0
(-2175 5975);
DISPLAY INVISIBLE (-2175 5975);
FORCEPROP 1 LAST OFFPAGE TRUE
J 0
(-1850 5850);
DISPLAY 0.872340 (-1850 5850);
PAINT GREEN (-1850 5850);
DISPLAY INVISIBLE (-1850 5850);
FORCEPROP 1 LAST COMMENT_BODY TRUE
J 0
(-2220 5880);
DISPLAY 0.872340 (-2220 5880);
PAINT GREEN (-2220 5880);
DISPLAY INVISIBLE (-2220 5880);
FORCEPROP 2 LAST PATH I301
J 0
(-1875 6025);
DISPLAY 0.680851 (-1875 6025);
DISPLAY INVISIBLE (-1875 6025);
FORCEADD Q_RES..1
(-2000 4175);
FORCEPROP 1 LAST LOCATION R3352
J 0
(-2150 4175);
DISPLAY 0.510638 (-2150 4175);
FORCEPROP 0 LAST $SEC 1
J 0
(-2125 4250);
DISPLAY 0.680851 (-2125 4250);
PAINT MONO (-2125 4250);
DISPLAY INVISIBLE (-2125 4250);
FORCEPROP 0 LAST CDS_SEC 1
J 0
(-2125 4250);
DISPLAY 0.680851 (-2125 4250);
DISPLAY INVISIBLE (-2125 4250);
FORCEPROP 1 LASTPIN (-2100 4175) $PN 1
J 0
(-2088 4187);
DISPLAY 0.787234 (-2088 4187);
PAINT MONO (-2088 4187);
FORCEPROP 1 LASTPIN (-1900 4175) $PN 2
J 0
(-1938 4187);
DISPLAY 0.787234 (-1938 4187);
PAINT MONO (-1938 4187);
FORCEPROP 1 LAST VALUE 0
J 2
(-1875 4175);
DISPLAY 0.510638 (-1875 4175);
FORCEPROP 1 LAST WATTAGE 1/16W
J 2
(-1575 4175);
DISPLAY 0.510638 (-1575 4175);
FORCEPROP 1 LAST MATERIAL CHIP
J 0
(-2275 4225);
DISPLAY 0.510638 (-2275 4225);
FORCEPROP 1 LAST TOLERANCE 5%
J 0
(-1825 4175);
DISPLAY 0.510638 (-1825 4175);
FORCEPROP 1 LAST PACK_TYPE 0402LF
J 0
(-2325 4175);
DISPLAY 0.510638 (-2325 4175);
FORCEPROP 2 LAST CDS_LIB pure_quanta
J 0
(-2000 4175);
DISPLAY INVISIBLE (-2000 4175);
FORCEPROP 1 LAST PATH I302
J 0
(-2050 4325);
DISPLAY 0.978723 (-2050 4325);
PAINT WHITE (-2050 4325);
DISPLAY INVISIBLE (-2050 4325);
FORCEPROP 1 LAST PART_NUMBER CS00002JB13
J 0
(-2125 4225);
DISPLAY 0.510638 (-2125 4225);
DISPLAY INVISIBLE (-2125 4225);
FORCEADD Q_RES..1
(-2000 4125);
FORCEPROP 1 LAST LOCATION R3353
J 0
(-2150 4125);
DISPLAY 0.510638 (-2150 4125);
FORCEPROP 0 LAST $SEC 1
J 0
(-1575 4150);
DISPLAY 0.680851 (-1575 4150);
PAINT MONO (-1575 4150);
DISPLAY INVISIBLE (-1575 4150);
FORCEPROP 0 LAST CDS_SEC 1
J 0
(-1575 4150);
DISPLAY 0.680851 (-1575 4150);
DISPLAY INVISIBLE (-1575 4150);
FORCEPROP 1 LASTPIN (-2100 4125) $PN 1
J 0
(-2088 4137);
DISPLAY 0.787234 (-2088 4137);
PAINT MONO (-2088 4137);
FORCEPROP 1 LASTPIN (-1900 4125) $PN 2
J 0
(-1938 4137);
DISPLAY 0.787234 (-1938 4137);
PAINT MONO (-1938 4137);
FORCEPROP 1 LAST VALUE 0
J 2
(-1875 4125);
DISPLAY 0.510638 (-1875 4125);
FORCEPROP 1 LAST WATTAGE 1/16W
J 2
(-1575 4125);
DISPLAY 0.510638 (-1575 4125);
FORCEPROP 1 LAST TOLERANCE 5%
J 0
(-1825 4125);
DISPLAY 0.510638 (-1825 4125);
FORCEPROP 1 LAST PACK_TYPE 0402LF
J 0
(-2325 4125);
DISPLAY 0.510638 (-2325 4125);
FORCEPROP 1 LAST MATERIAL CHIP
J 0
(-2275 4175);
DISPLAY 0.510638 (-2275 4175);
DISPLAY INVISIBLE (-2275 4175);
FORCEPROP 2 LAST CDS_LIB pure_quanta
J 0
(-2000 4125);
DISPLAY INVISIBLE (-2000 4125);
FORCEPROP 1 LAST PATH I303
J 0
(-2050 4275);
DISPLAY 0.978723 (-2050 4275);
PAINT WHITE (-2050 4275);
DISPLAY INVISIBLE (-2050 4275);
FORCEPROP 1 LAST PART_NUMBER CS00002JB13
J 0
(-2125 4175);
DISPLAY 0.510638 (-2125 4175);
DISPLAY INVISIBLE (-2125 4175);
FORCEADD OFFPAGE..2
(-675 4925);
FORCEPROP 2 LAST $XR0 122 
J 0
(-486 4925);
DISPLAY 0.638298 (-486 4925);
PAINT MONO (-486 4925);
FORCEPROP 2 LAST CDS_LIB standard
J 0
(-675 4925);
DISPLAY INVISIBLE (-675 4925);
FORCEPROP 1 LAST OFFPAGE TRUE
J 0
(-350 4800);
DISPLAY 0.872340 (-350 4800);
PAINT GREEN (-350 4800);
DISPLAY INVISIBLE (-350 4800);
FORCEPROP 1 LAST COMMENT_BODY TRUE
J 0
(-720 4830);
DISPLAY 0.872340 (-720 4830);
PAINT GREEN (-720 4830);
DISPLAY INVISIBLE (-720 4830);
FORCEPROP 2 LAST PATH I304
J 0
(-500 5000);
DISPLAY 0.680851 (-500 5000);
DISPLAY INVISIBLE (-500 5000);
FORCEADD OFFPAGE..2
(-675 4875);
FORCEPROP 2 LAST $XR0 122 
J 0
(-486 4875);
DISPLAY 0.638298 (-486 4875);
PAINT MONO (-486 4875);
FORCEPROP 2 LAST CDS_LIB standard
J 0
(-675 4875);
DISPLAY INVISIBLE (-675 4875);
FORCEPROP 1 LAST OFFPAGE TRUE
J 0
(-350 4750);
DISPLAY 0.872340 (-350 4750);
PAINT GREEN (-350 4750);
DISPLAY INVISIBLE (-350 4750);
FORCEPROP 1 LAST COMMENT_BODY TRUE
J 0
(-720 4780);
DISPLAY 0.872340 (-720 4780);
PAINT GREEN (-720 4780);
DISPLAY INVISIBLE (-720 4780);
FORCEPROP 2 LAST PATH I305
J 0
(-500 4950);
DISPLAY 0.680851 (-500 4950);
DISPLAY INVISIBLE (-500 4950);
FORCEADD Q_RES..1
(-2000 4875);
FORCEPROP 1 LAST LOCATION R3355
J 0
(-2150 4875);
DISPLAY 0.510638 (-2150 4875);
FORCEPROP 0 LAST $SEC 1
J 0
(-1575 4900);
DISPLAY 0.680851 (-1575 4900);
PAINT MONO (-1575 4900);
DISPLAY INVISIBLE (-1575 4900);
FORCEPROP 0 LAST CDS_SEC 1
J 0
(-1575 4900);
DISPLAY 0.680851 (-1575 4900);
DISPLAY INVISIBLE (-1575 4900);
FORCEPROP 1 LASTPIN (-2100 4875) $PN 1
J 0
(-2088 4887);
DISPLAY 0.787234 (-2088 4887);
PAINT MONO (-2088 4887);
FORCEPROP 1 LASTPIN (-1900 4875) $PN 2
J 0
(-1938 4887);
DISPLAY 0.787234 (-1938 4887);
PAINT MONO (-1938 4887);
FORCEPROP 1 LAST PACK_TYPE 0402LF
J 0
(-2325 4875);
DISPLAY 0.510638 (-2325 4875);
FORCEPROP 1 LAST VALUE 0
J 2
(-1875 4875);
DISPLAY 0.510638 (-1875 4875);
FORCEPROP 1 LAST WATTAGE 1/16W
J 2
(-1575 4875);
DISPLAY 0.510638 (-1575 4875);
FORCEPROP 1 LAST TOLERANCE 5%
J 0
(-1825 4875);
DISPLAY 0.510638 (-1825 4875);
FORCEPROP 1 LAST MATERIAL CHIP
J 0
(-2275 4925);
DISPLAY 0.510638 (-2275 4925);
DISPLAY INVISIBLE (-2275 4925);
FORCEPROP 2 LAST CDS_LIB pure_quanta
J 0
(-2000 4875);
DISPLAY INVISIBLE (-2000 4875);
FORCEPROP 1 LAST PATH I306
J 0
(-2050 5025);
DISPLAY 0.978723 (-2050 5025);
PAINT WHITE (-2050 5025);
DISPLAY INVISIBLE (-2050 5025);
FORCEPROP 1 LAST PART_NUMBER CS00002JB13
J 0
(-2125 4925);
DISPLAY 0.510638 (-2125 4925);
DISPLAY INVISIBLE (-2125 4925);
FORCEADD Q_RES..1
(-2000 4925);
FORCEPROP 1 LAST LOCATION R3354
J 0
(-2150 4925);
DISPLAY 0.510638 (-2150 4925);
FORCEPROP 0 LAST $SEC 1
J 0
(-2125 5000);
DISPLAY 0.680851 (-2125 5000);
PAINT MONO (-2125 5000);
DISPLAY INVISIBLE (-2125 5000);
FORCEPROP 0 LAST CDS_SEC 1
J 0
(-2125 5000);
DISPLAY 0.680851 (-2125 5000);
DISPLAY INVISIBLE (-2125 5000);
FORCEPROP 1 LASTPIN (-2100 4925) $PN 1
J 0
(-2088 4937);
DISPLAY 0.787234 (-2088 4937);
PAINT MONO (-2088 4937);
FORCEPROP 1 LASTPIN (-1900 4925) $PN 2
J 0
(-1938 4937);
DISPLAY 0.787234 (-1938 4937);
PAINT MONO (-1938 4937);
FORCEPROP 1 LAST PACK_TYPE 0402LF
J 0
(-2325 4925);
DISPLAY 0.510638 (-2325 4925);
FORCEPROP 1 LAST VALUE 0
J 2
(-1875 4925);
DISPLAY 0.510638 (-1875 4925);
FORCEPROP 1 LAST TOLERANCE 5%
J 0
(-1825 4925);
DISPLAY 0.510638 (-1825 4925);
FORCEPROP 1 LAST MATERIAL CHIP
J 0
(-2275 4975);
DISPLAY 0.510638 (-2275 4975);
FORCEPROP 1 LAST WATTAGE 1/16W
J 2
(-1575 4925);
DISPLAY 0.510638 (-1575 4925);
FORCEPROP 2 LAST CDS_LIB pure_quanta
J 0
(-2000 4925);
DISPLAY INVISIBLE (-2000 4925);
FORCEPROP 1 LAST PATH I307
J 0
(-2050 5075);
DISPLAY 0.978723 (-2050 5075);
PAINT WHITE (-2050 5075);
DISPLAY INVISIBLE (-2050 5075);
FORCEPROP 1 LAST PART_NUMBER CS00002JB13
J 0
(-2125 4975);
DISPLAY 0.510638 (-2125 4975);
DISPLAY INVISIBLE (-2125 4975);
FORCEADD Q_RES..1
(-2000 4775);
FORCEPROP 1 LAST LOCATION R3194
J 0
(-2150 4775);
DISPLAY 0.510638 (-2150 4775);
FORCEPROP 0 LAST $SEC 1
J 0
(-2125 4850);
DISPLAY 0.680851 (-2125 4850);
PAINT MONO (-2125 4850);
DISPLAY INVISIBLE (-2125 4850);
FORCEPROP 0 LAST CDS_SEC 1
J 0
(-2125 4850);
DISPLAY 0.680851 (-2125 4850);
DISPLAY INVISIBLE (-2125 4850);
FORCEPROP 1 LASTPIN (-2100 4775) $PN 1
J 0
(-2088 4787);
DISPLAY 0.787234 (-2088 4787);
PAINT MONO (-2088 4787);
FORCEPROP 1 LASTPIN (-1900 4775) $PN 2
J 0
(-1938 4787);
DISPLAY 0.787234 (-1938 4787);
PAINT MONO (-1938 4787);
FORCEPROP 1 LAST MATERIAL CHIP
J 0
(-2275 4825);
DISPLAY 0.510638 (-2275 4825);
FORCEPROP 1 LAST PACK_TYPE 0402LF
J 0
(-2325 4775);
DISPLAY 0.510638 (-2325 4775);
FORCEPROP 1 LAST VALUE 0
J 2
(-1875 4775);
DISPLAY 0.510638 (-1875 4775);
FORCEPROP 1 LAST WATTAGE 1/16W
J 2
(-1575 4775);
DISPLAY 0.510638 (-1575 4775);
FORCEPROP 1 LAST TOLERANCE 5%
J 0
(-1825 4775);
DISPLAY 0.510638 (-1825 4775);
FORCEPROP 2 LAST CDS_LIB pure_quanta
J 0
(-2000 4775);
DISPLAY INVISIBLE (-2000 4775);
FORCEPROP 1 LAST PATH I308
J 0
(-2050 4925);
DISPLAY 0.978723 (-2050 4925);
PAINT WHITE (-2050 4925);
DISPLAY INVISIBLE (-2050 4925);
FORCEPROP 1 LAST PART_NUMBER CS00002JB13
J 0
(-2125 4825);
DISPLAY 0.510638 (-2125 4825);
DISPLAY INVISIBLE (-2125 4825);
FORCEADD Q_RES..1
(-2000 4725);
FORCEPROP 1 LAST LOCATION R3195
J 0
(-2150 4725);
DISPLAY 0.510638 (-2150 4725);
FORCEPROP 0 LAST $SEC 1
J 0
(-1575 4750);
DISPLAY 0.680851 (-1575 4750);
PAINT MONO (-1575 4750);
DISPLAY INVISIBLE (-1575 4750);
FORCEPROP 0 LAST CDS_SEC 1
J 0
(-1575 4750);
DISPLAY 0.680851 (-1575 4750);
DISPLAY INVISIBLE (-1575 4750);
FORCEPROP 1 LASTPIN (-2100 4725) $PN 1
J 0
(-2088 4737);
DISPLAY 0.787234 (-2088 4737);
PAINT MONO (-2088 4737);
FORCEPROP 1 LASTPIN (-1900 4725) $PN 2
J 0
(-1938 4737);
DISPLAY 0.787234 (-1938 4737);
PAINT MONO (-1938 4737);
FORCEPROP 1 LAST TOLERANCE 5%
J 0
(-1825 4725);
DISPLAY 0.510638 (-1825 4725);
FORCEPROP 1 LAST PACK_TYPE 0402LF
J 0
(-2325 4725);
DISPLAY 0.510638 (-2325 4725);
FORCEPROP 1 LAST WATTAGE 1/16W
J 2
(-1575 4725);
DISPLAY 0.510638 (-1575 4725);
FORCEPROP 1 LAST VALUE 0
J 2
(-1875 4725);
DISPLAY 0.510638 (-1875 4725);
FORCEPROP 1 LAST MATERIAL CHIP
J 0
(-2275 4775);
DISPLAY 0.510638 (-2275 4775);
DISPLAY INVISIBLE (-2275 4775);
FORCEPROP 2 LAST CDS_LIB pure_quanta
J 0
(-2000 4725);
DISPLAY INVISIBLE (-2000 4725);
FORCEPROP 1 LAST PATH I309
J 0
(-2050 4875);
DISPLAY 0.978723 (-2050 4875);
PAINT WHITE (-2050 4875);
DISPLAY INVISIBLE (-2050 4875);
FORCEPROP 1 LAST PART_NUMBER CS00002JB13
J 0
(-2125 4775);
DISPLAY 0.510638 (-2125 4775);
DISPLAY INVISIBLE (-2125 4775);
FORCEADD OFFPAGE..2
(-675 4725);
FORCEPROP 2 LAST $XR0 137 
J 0
(-486 4725);
DISPLAY 0.638298 (-486 4725);
PAINT MONO (-486 4725);
FORCEPROP 2 LAST CDS_LIB standard
J 0
(-675 4725);
DISPLAY INVISIBLE (-675 4725);
FORCEPROP 1 LAST OFFPAGE TRUE
J 0
(-350 4600);
DISPLAY 0.872340 (-350 4600);
PAINT GREEN (-350 4600);
DISPLAY INVISIBLE (-350 4600);
FORCEPROP 1 LAST COMMENT_BODY TRUE
J 0
(-720 4630);
DISPLAY 0.872340 (-720 4630);
PAINT GREEN (-720 4630);
DISPLAY INVISIBLE (-720 4630);
FORCEPROP 2 LAST PATH I310
J 0
(-500 4800);
DISPLAY 0.680851 (-500 4800);
DISPLAY INVISIBLE (-500 4800);
FORCEADD OFFPAGE..2
(-675 4775);
FORCEPROP 2 LAST $XR0 137 
J 0
(-486 4775);
DISPLAY 0.638298 (-486 4775);
PAINT MONO (-486 4775);
FORCEPROP 2 LAST CDS_LIB standard
J 0
(-675 4775);
DISPLAY INVISIBLE (-675 4775);
FORCEPROP 1 LAST OFFPAGE TRUE
J 0
(-350 4650);
DISPLAY 0.872340 (-350 4650);
PAINT GREEN (-350 4650);
DISPLAY INVISIBLE (-350 4650);
FORCEPROP 1 LAST COMMENT_BODY TRUE
J 0
(-720 4680);
DISPLAY 0.872340 (-720 4680);
PAINT GREEN (-720 4680);
DISPLAY INVISIBLE (-720 4680);
FORCEPROP 2 LAST PATH I311
J 0
(-500 4850);
DISPLAY 0.680851 (-500 4850);
DISPLAY INVISIBLE (-500 4850);
FORCEADD Q_RES..1
(-2000 4625);
FORCEPROP 1 LAST LOCATION R3196
J 0
(-2150 4625);
DISPLAY 0.510638 (-2150 4625);
FORCEPROP 0 LAST $SEC 1
J 0
(-2125 4700);
DISPLAY 0.680851 (-2125 4700);
PAINT MONO (-2125 4700);
DISPLAY INVISIBLE (-2125 4700);
FORCEPROP 0 LAST CDS_SEC 1
J 0
(-2125 4700);
DISPLAY 0.680851 (-2125 4700);
DISPLAY INVISIBLE (-2125 4700);
FORCEPROP 1 LASTPIN (-2100 4625) $PN 1
J 0
(-2088 4637);
DISPLAY 0.787234 (-2088 4637);
PAINT MONO (-2088 4637);
FORCEPROP 1 LASTPIN (-1900 4625) $PN 2
J 0
(-1938 4637);
DISPLAY 0.787234 (-1938 4637);
PAINT MONO (-1938 4637);
FORCEPROP 1 LAST TOLERANCE 5%
J 0
(-1825 4625);
DISPLAY 0.510638 (-1825 4625);
FORCEPROP 1 LAST MATERIAL CHIP
J 0
(-2275 4675);
DISPLAY 0.510638 (-2275 4675);
FORCEPROP 1 LAST VALUE 0
J 2
(-1875 4625);
DISPLAY 0.510638 (-1875 4625);
FORCEPROP 1 LAST PACK_TYPE 0402LF
J 0
(-2325 4625);
DISPLAY 0.510638 (-2325 4625);
FORCEPROP 1 LAST WATTAGE 1/16W
J 2
(-1575 4625);
DISPLAY 0.510638 (-1575 4625);
FORCEPROP 2 LAST CDS_LIB pure_quanta
J 0
(-2000 4625);
DISPLAY INVISIBLE (-2000 4625);
FORCEPROP 1 LAST PATH I312
J 0
(-2050 4775);
DISPLAY 0.978723 (-2050 4775);
PAINT WHITE (-2050 4775);
DISPLAY INVISIBLE (-2050 4775);
FORCEPROP 1 LAST PART_NUMBER CS00002JB13
J 0
(-2125 4675);
DISPLAY 0.510638 (-2125 4675);
DISPLAY INVISIBLE (-2125 4675);
FORCEADD Q_RES..1
(-2000 4575);
FORCEPROP 1 LAST LOCATION R3197
J 0
(-2150 4575);
DISPLAY 0.510638 (-2150 4575);
FORCEPROP 0 LAST $SEC 1
J 0
(-1575 4600);
DISPLAY 0.680851 (-1575 4600);
PAINT MONO (-1575 4600);
DISPLAY INVISIBLE (-1575 4600);
FORCEPROP 0 LAST CDS_SEC 1
J 0
(-1575 4600);
DISPLAY 0.680851 (-1575 4600);
DISPLAY INVISIBLE (-1575 4600);
FORCEPROP 1 LASTPIN (-2100 4575) $PN 1
J 0
(-2088 4587);
DISPLAY 0.787234 (-2088 4587);
PAINT MONO (-2088 4587);
FORCEPROP 1 LASTPIN (-1900 4575) $PN 2
J 0
(-1938 4587);
DISPLAY 0.787234 (-1938 4587);
PAINT MONO (-1938 4587);
FORCEPROP 1 LAST VALUE 0
J 2
(-1875 4575);
DISPLAY 0.510638 (-1875 4575);
FORCEPROP 1 LAST TOLERANCE 5%
J 0
(-1825 4575);
DISPLAY 0.510638 (-1825 4575);
FORCEPROP 1 LAST PACK_TYPE 0402LF
J 0
(-2325 4575);
DISPLAY 0.510638 (-2325 4575);
FORCEPROP 1 LAST WATTAGE 1/16W
J 2
(-1575 4575);
DISPLAY 0.510638 (-1575 4575);
FORCEPROP 1 LAST MATERIAL CHIP
J 0
(-2275 4625);
DISPLAY 0.510638 (-2275 4625);
DISPLAY INVISIBLE (-2275 4625);
FORCEPROP 2 LAST CDS_LIB pure_quanta
J 0
(-2000 4575);
DISPLAY INVISIBLE (-2000 4575);
FORCEPROP 1 LAST PATH I313
J 0
(-2050 4725);
DISPLAY 0.978723 (-2050 4725);
PAINT WHITE (-2050 4725);
DISPLAY INVISIBLE (-2050 4725);
FORCEPROP 1 LAST PART_NUMBER CS00002JB13
J 0
(-2125 4625);
DISPLAY 0.510638 (-2125 4625);
DISPLAY INVISIBLE (-2125 4625);
FORCEADD OFFPAGE..2
(-675 4575);
FORCEPROP 2 LAST $XR0 137 
J 0
(-486 4575);
DISPLAY 0.638298 (-486 4575);
PAINT MONO (-486 4575);
FORCEPROP 2 LAST CDS_LIB standard
J 0
(-675 4575);
DISPLAY INVISIBLE (-675 4575);
FORCEPROP 1 LAST OFFPAGE TRUE
J 0
(-350 4450);
DISPLAY 0.872340 (-350 4450);
PAINT GREEN (-350 4450);
DISPLAY INVISIBLE (-350 4450);
FORCEPROP 1 LAST COMMENT_BODY TRUE
J 0
(-720 4480);
DISPLAY 0.872340 (-720 4480);
PAINT GREEN (-720 4480);
DISPLAY INVISIBLE (-720 4480);
FORCEPROP 2 LAST PATH I314
J 0
(-500 4650);
DISPLAY 0.680851 (-500 4650);
DISPLAY INVISIBLE (-500 4650);
FORCEADD OFFPAGE..2
(-675 4625);
FORCEPROP 2 LAST $XR0 137 
J 0
(-486 4625);
DISPLAY 0.638298 (-486 4625);
PAINT MONO (-486 4625);
FORCEPROP 2 LAST CDS_LIB standard
J 0
(-675 4625);
DISPLAY INVISIBLE (-675 4625);
FORCEPROP 1 LAST OFFPAGE TRUE
J 0
(-350 4500);
DISPLAY 0.872340 (-350 4500);
PAINT GREEN (-350 4500);
DISPLAY INVISIBLE (-350 4500);
FORCEPROP 1 LAST COMMENT_BODY TRUE
J 0
(-720 4530);
DISPLAY 0.872340 (-720 4530);
PAINT GREEN (-720 4530);
DISPLAY INVISIBLE (-720 4530);
FORCEPROP 2 LAST PATH I315
J 0
(-500 4700);
DISPLAY 0.680851 (-500 4700);
DISPLAY INVISIBLE (-500 4700);
FORCEADD Q_RES..1
(-2000 4475);
FORCEPROP 1 LAST LOCATION R3198
J 0
(-2150 4475);
DISPLAY 0.510638 (-2150 4475);
FORCEPROP 0 LAST $SEC 1
J 0
(-2125 4550);
DISPLAY 0.680851 (-2125 4550);
PAINT MONO (-2125 4550);
DISPLAY INVISIBLE (-2125 4550);
FORCEPROP 0 LAST CDS_SEC 1
J 0
(-2125 4550);
DISPLAY 0.680851 (-2125 4550);
DISPLAY INVISIBLE (-2125 4550);
FORCEPROP 1 LASTPIN (-2100 4475) $PN 1
J 0
(-2088 4487);
DISPLAY 0.787234 (-2088 4487);
PAINT MONO (-2088 4487);
FORCEPROP 1 LASTPIN (-1900 4475) $PN 2
J 0
(-1938 4487);
DISPLAY 0.787234 (-1938 4487);
PAINT MONO (-1938 4487);
FORCEPROP 1 LAST WATTAGE 1/16W
J 2
(-1575 4475);
DISPLAY 0.510638 (-1575 4475);
FORCEPROP 1 LAST MATERIAL CHIP
J 0
(-2275 4525);
DISPLAY 0.510638 (-2275 4525);
FORCEPROP 1 LAST VALUE 0
J 2
(-1875 4475);
DISPLAY 0.510638 (-1875 4475);
FORCEPROP 1 LAST PACK_TYPE 0402LF
J 0
(-2325 4475);
DISPLAY 0.510638 (-2325 4475);
FORCEPROP 1 LAST TOLERANCE 5%
J 0
(-1825 4475);
DISPLAY 0.510638 (-1825 4475);
FORCEPROP 2 LAST CDS_LIB pure_quanta
J 0
(-2000 4475);
DISPLAY INVISIBLE (-2000 4475);
FORCEPROP 1 LAST PATH I316
J 0
(-2050 4625);
DISPLAY 0.978723 (-2050 4625);
PAINT WHITE (-2050 4625);
DISPLAY INVISIBLE (-2050 4625);
FORCEPROP 1 LAST PART_NUMBER CS00002JB13
J 0
(-2125 4525);
DISPLAY 0.510638 (-2125 4525);
DISPLAY INVISIBLE (-2125 4525);
FORCEADD Q_RES..1
(-2000 4425);
FORCEPROP 1 LAST LOCATION R3199
J 0
(-2150 4425);
DISPLAY 0.510638 (-2150 4425);
FORCEPROP 0 LAST $SEC 1
J 0
(-1575 4450);
DISPLAY 0.680851 (-1575 4450);
PAINT MONO (-1575 4450);
DISPLAY INVISIBLE (-1575 4450);
FORCEPROP 0 LAST CDS_SEC 1
J 0
(-1575 4450);
DISPLAY 0.680851 (-1575 4450);
DISPLAY INVISIBLE (-1575 4450);
FORCEPROP 1 LASTPIN (-2100 4425) $PN 1
J 0
(-2088 4437);
DISPLAY 0.787234 (-2088 4437);
PAINT MONO (-2088 4437);
FORCEPROP 1 LASTPIN (-1900 4425) $PN 2
J 0
(-1938 4437);
DISPLAY 0.787234 (-1938 4437);
PAINT MONO (-1938 4437);
FORCEPROP 1 LAST PACK_TYPE 0402LF
J 0
(-2325 4425);
DISPLAY 0.510638 (-2325 4425);
FORCEPROP 1 LAST VALUE 0
J 2
(-1875 4425);
DISPLAY 0.510638 (-1875 4425);
FORCEPROP 1 LAST TOLERANCE 5%
J 0
(-1825 4425);
DISPLAY 0.510638 (-1825 4425);
FORCEPROP 1 LAST WATTAGE 1/16W
J 2
(-1575 4425);
DISPLAY 0.510638 (-1575 4425);
FORCEPROP 1 LAST MATERIAL CHIP
J 0
(-2275 4475);
DISPLAY 0.510638 (-2275 4475);
DISPLAY INVISIBLE (-2275 4475);
FORCEPROP 2 LAST CDS_LIB pure_quanta
J 0
(-2000 4425);
DISPLAY INVISIBLE (-2000 4425);
FORCEPROP 1 LAST PATH I317
J 0
(-2050 4575);
DISPLAY 0.978723 (-2050 4575);
PAINT WHITE (-2050 4575);
DISPLAY INVISIBLE (-2050 4575);
FORCEPROP 1 LAST PART_NUMBER CS00002JB13
J 0
(-2125 4475);
DISPLAY 0.510638 (-2125 4475);
DISPLAY INVISIBLE (-2125 4475);
FORCEADD OFFPAGE..2
(-675 4425);
FORCEPROP 2 LAST $XR0 137 
J 0
(-486 4425);
DISPLAY 0.638298 (-486 4425);
PAINT MONO (-486 4425);
FORCEPROP 2 LAST CDS_LIB standard
J 0
(-675 4425);
DISPLAY INVISIBLE (-675 4425);
FORCEPROP 1 LAST OFFPAGE TRUE
J 0
(-350 4300);
DISPLAY 0.872340 (-350 4300);
PAINT GREEN (-350 4300);
DISPLAY INVISIBLE (-350 4300);
FORCEPROP 1 LAST COMMENT_BODY TRUE
J 0
(-720 4330);
DISPLAY 0.872340 (-720 4330);
PAINT GREEN (-720 4330);
DISPLAY INVISIBLE (-720 4330);
FORCEPROP 2 LAST PATH I318
J 0
(-500 4500);
DISPLAY 0.680851 (-500 4500);
DISPLAY INVISIBLE (-500 4500);
FORCEADD OFFPAGE..2
(-675 4475);
FORCEPROP 2 LAST $XR0 137 
J 0
(-486 4475);
DISPLAY 0.638298 (-486 4475);
PAINT MONO (-486 4475);
FORCEPROP 2 LAST CDS_LIB standard
J 0
(-675 4475);
DISPLAY INVISIBLE (-675 4475);
FORCEPROP 1 LAST OFFPAGE TRUE
J 0
(-350 4350);
DISPLAY 0.872340 (-350 4350);
PAINT GREEN (-350 4350);
DISPLAY INVISIBLE (-350 4350);
FORCEPROP 1 LAST COMMENT_BODY TRUE
J 0
(-720 4380);
DISPLAY 0.872340 (-720 4380);
PAINT GREEN (-720 4380);
DISPLAY INVISIBLE (-720 4380);
FORCEPROP 2 LAST PATH I319
J 0
(-500 4550);
DISPLAY 0.680851 (-500 4550);
DISPLAY INVISIBLE (-500 4550);
FORCEADD Q_RES..1
(-2000 4325);
FORCEPROP 1 LAST LOCATION R3200
J 0
(-2150 4325);
DISPLAY 0.510638 (-2150 4325);
FORCEPROP 0 LAST $SEC 1
J 0
(-2125 4400);
DISPLAY 0.680851 (-2125 4400);
PAINT MONO (-2125 4400);
DISPLAY INVISIBLE (-2125 4400);
FORCEPROP 0 LAST CDS_SEC 1
J 0
(-2125 4400);
DISPLAY 0.680851 (-2125 4400);
DISPLAY INVISIBLE (-2125 4400);
FORCEPROP 1 LASTPIN (-2100 4325) $PN 1
J 0
(-2088 4337);
DISPLAY 0.787234 (-2088 4337);
PAINT MONO (-2088 4337);
FORCEPROP 1 LASTPIN (-1900 4325) $PN 2
J 0
(-1938 4337);
DISPLAY 0.787234 (-1938 4337);
PAINT MONO (-1938 4337);
FORCEPROP 1 LAST MATERIAL CHIP
J 0
(-2275 4375);
DISPLAY 0.510638 (-2275 4375);
FORCEPROP 1 LAST WATTAGE 1/16W
J 2
(-1575 4325);
DISPLAY 0.510638 (-1575 4325);
FORCEPROP 1 LAST VALUE 0
J 2
(-1875 4325);
DISPLAY 0.510638 (-1875 4325);
FORCEPROP 1 LAST TOLERANCE 5%
J 0
(-1825 4325);
DISPLAY 0.510638 (-1825 4325);
FORCEPROP 1 LAST PACK_TYPE 0402LF
J 0
(-2325 4325);
DISPLAY 0.510638 (-2325 4325);
FORCEPROP 2 LAST CDS_LIB pure_quanta
J 0
(-2000 4325);
DISPLAY INVISIBLE (-2000 4325);
FORCEPROP 1 LAST PATH I320
J 0
(-2050 4475);
DISPLAY 0.978723 (-2050 4475);
PAINT WHITE (-2050 4475);
DISPLAY INVISIBLE (-2050 4475);
FORCEPROP 1 LAST PART_NUMBER CS00002JB13
J 0
(-2125 4375);
DISPLAY 0.510638 (-2125 4375);
DISPLAY INVISIBLE (-2125 4375);
FORCEADD Q_RES..1
(-2000 4275);
FORCEPROP 1 LAST LOCATION R3201
J 0
(-2150 4275);
DISPLAY 0.510638 (-2150 4275);
FORCEPROP 0 LAST $SEC 1
J 0
(-1575 4300);
DISPLAY 0.680851 (-1575 4300);
PAINT MONO (-1575 4300);
DISPLAY INVISIBLE (-1575 4300);
FORCEPROP 0 LAST CDS_SEC 1
J 0
(-1575 4300);
DISPLAY 0.680851 (-1575 4300);
DISPLAY INVISIBLE (-1575 4300);
FORCEPROP 1 LASTPIN (-2100 4275) $PN 1
J 0
(-2088 4287);
DISPLAY 0.787234 (-2088 4287);
PAINT MONO (-2088 4287);
FORCEPROP 1 LASTPIN (-1900 4275) $PN 2
J 0
(-1938 4287);
DISPLAY 0.787234 (-1938 4287);
PAINT MONO (-1938 4287);
FORCEPROP 1 LAST WATTAGE 1/16W
J 2
(-1575 4275);
DISPLAY 0.510638 (-1575 4275);
FORCEPROP 1 LAST TOLERANCE 5%
J 0
(-1825 4275);
DISPLAY 0.510638 (-1825 4275);
FORCEPROP 1 LAST VALUE 0
J 2
(-1875 4275);
DISPLAY 0.510638 (-1875 4275);
FORCEPROP 1 LAST PACK_TYPE 0402LF
J 0
(-2325 4275);
DISPLAY 0.510638 (-2325 4275);
FORCEPROP 1 LAST MATERIAL CHIP
J 0
(-2275 4325);
DISPLAY 0.510638 (-2275 4325);
DISPLAY INVISIBLE (-2275 4325);
FORCEPROP 2 LAST CDS_LIB pure_quanta
J 0
(-2000 4275);
DISPLAY INVISIBLE (-2000 4275);
FORCEPROP 1 LAST PATH I321
J 0
(-2050 4425);
DISPLAY 0.978723 (-2050 4425);
PAINT WHITE (-2050 4425);
DISPLAY INVISIBLE (-2050 4425);
FORCEPROP 1 LAST PART_NUMBER CS00002JB13
J 0
(-2125 4325);
DISPLAY 0.510638 (-2125 4325);
DISPLAY INVISIBLE (-2125 4325);
FORCEADD OFFPAGE..2
(-675 4275);
FORCEPROP 2 LAST $XR0 137 
J 0
(-486 4275);
DISPLAY 0.638298 (-486 4275);
PAINT MONO (-486 4275);
FORCEPROP 2 LAST CDS_LIB standard
J 0
(-675 4275);
DISPLAY INVISIBLE (-675 4275);
FORCEPROP 1 LAST OFFPAGE TRUE
J 0
(-350 4150);
DISPLAY 0.872340 (-350 4150);
PAINT GREEN (-350 4150);
DISPLAY INVISIBLE (-350 4150);
FORCEPROP 1 LAST COMMENT_BODY TRUE
J 0
(-720 4180);
DISPLAY 0.872340 (-720 4180);
PAINT GREEN (-720 4180);
DISPLAY INVISIBLE (-720 4180);
FORCEPROP 2 LAST PATH I322
J 0
(-500 4350);
DISPLAY 0.680851 (-500 4350);
DISPLAY INVISIBLE (-500 4350);
FORCEADD OFFPAGE..2
(-675 4325);
FORCEPROP 2 LAST $XR0 137 
J 0
(-486 4325);
DISPLAY 0.638298 (-486 4325);
PAINT MONO (-486 4325);
FORCEPROP 2 LAST CDS_LIB standard
J 0
(-675 4325);
DISPLAY INVISIBLE (-675 4325);
FORCEPROP 1 LAST OFFPAGE TRUE
J 0
(-350 4200);
DISPLAY 0.872340 (-350 4200);
PAINT GREEN (-350 4200);
DISPLAY INVISIBLE (-350 4200);
FORCEPROP 1 LAST COMMENT_BODY TRUE
J 0
(-720 4230);
DISPLAY 0.872340 (-720 4230);
PAINT GREEN (-720 4230);
DISPLAY INVISIBLE (-720 4230);
FORCEPROP 2 LAST PATH I323
J 0
(-500 4400);
DISPLAY 0.680851 (-500 4400);
DISPLAY INVISIBLE (-500 4400);
FORCEADD OFFPAGE..2
(-675 4025);
FORCEPROP 2 LAST $XR0 144 
J 0
(-486 4025);
DISPLAY 0.638298 (-486 4025);
PAINT MONO (-486 4025);
FORCEPROP 2 LAST CDS_LIB standard
J 0
(-675 4025);
DISPLAY INVISIBLE (-675 4025);
FORCEPROP 1 LAST OFFPAGE TRUE
J 0
(-350 3900);
DISPLAY 0.872340 (-350 3900);
PAINT GREEN (-350 3900);
DISPLAY INVISIBLE (-350 3900);
FORCEPROP 1 LAST COMMENT_BODY TRUE
J 0
(-720 3930);
DISPLAY 0.872340 (-720 3930);
PAINT GREEN (-720 3930);
DISPLAY INVISIBLE (-720 3930);
FORCEPROP 2 LAST PATH I324
J 0
(-500 4100);
DISPLAY 0.680851 (-500 4100);
DISPLAY INVISIBLE (-500 4100);
FORCEADD OFFPAGE..2
(-675 3975);
FORCEPROP 2 LAST $XR0 144 
J 0
(-486 3975);
DISPLAY 0.638298 (-486 3975);
PAINT MONO (-486 3975);
FORCEPROP 2 LAST CDS_LIB standard
J 0
(-675 3975);
DISPLAY INVISIBLE (-675 3975);
FORCEPROP 1 LAST OFFPAGE TRUE
J 0
(-350 3850);
DISPLAY 0.872340 (-350 3850);
PAINT GREEN (-350 3850);
DISPLAY INVISIBLE (-350 3850);
FORCEPROP 1 LAST COMMENT_BODY TRUE
J 0
(-720 3880);
DISPLAY 0.872340 (-720 3880);
PAINT GREEN (-720 3880);
DISPLAY INVISIBLE (-720 3880);
FORCEPROP 2 LAST PATH I325
J 0
(-500 4050);
DISPLAY 0.680851 (-500 4050);
DISPLAY INVISIBLE (-500 4050);
FORCEADD Q_RES..1
(-2000 3975);
FORCEPROP 1 LAST LOCATION R4306
J 0
(-2150 3975);
DISPLAY 0.510638 (-2150 3975);
FORCEPROP 0 LAST $SEC 1
J 0
(-1575 4000);
DISPLAY 0.680851 (-1575 4000);
PAINT MONO (-1575 4000);
DISPLAY INVISIBLE (-1575 4000);
FORCEPROP 0 LAST CDS_SEC 1
J 0
(-1575 4000);
DISPLAY 0.680851 (-1575 4000);
DISPLAY INVISIBLE (-1575 4000);
FORCEPROP 1 LASTPIN (-2100 3975) $PN 1
J 0
(-2088 3987);
DISPLAY 0.787234 (-2088 3987);
PAINT MONO (-2088 3987);
FORCEPROP 1 LASTPIN (-1900 3975) $PN 2
J 0
(-1938 3987);
DISPLAY 0.787234 (-1938 3987);
PAINT MONO (-1938 3987);
FORCEPROP 1 LAST PACK_TYPE 0402LF
J 0
(-2325 3975);
DISPLAY 0.510638 (-2325 3975);
FORCEPROP 1 LAST VALUE 0
J 2
(-1875 3975);
DISPLAY 0.510638 (-1875 3975);
FORCEPROP 1 LAST TOLERANCE 5%
J 0
(-1825 3975);
DISPLAY 0.510638 (-1825 3975);
FORCEPROP 1 LAST WATTAGE 1/16W
J 2
(-1575 3975);
DISPLAY 0.510638 (-1575 3975);
FORCEPROP 1 LAST MATERIAL CHIP
J 0
(-2275 4025);
DISPLAY 0.510638 (-2275 4025);
DISPLAY INVISIBLE (-2275 4025);
FORCEPROP 2 LAST CDS_LIB pure_quanta
J 0
(-2000 3975);
DISPLAY INVISIBLE (-2000 3975);
FORCEPROP 1 LAST PATH I326
J 0
(-2050 4125);
DISPLAY 0.978723 (-2050 4125);
PAINT WHITE (-2050 4125);
DISPLAY INVISIBLE (-2050 4125);
FORCEPROP 1 LAST PART_NUMBER CS00002JB13
J 0
(-2125 4025);
DISPLAY 0.510638 (-2125 4025);
DISPLAY INVISIBLE (-2125 4025);
FORCEADD Q_RES..1
(-2000 4025);
FORCEPROP 1 LAST LOCATION R4305
J 0
(-2150 4025);
DISPLAY 0.510638 (-2150 4025);
FORCEPROP 0 LAST $SEC 1
J 0
(-2125 4100);
DISPLAY 0.680851 (-2125 4100);
PAINT MONO (-2125 4100);
DISPLAY INVISIBLE (-2125 4100);
FORCEPROP 0 LAST CDS_SEC 1
J 0
(-2125 4100);
DISPLAY 0.680851 (-2125 4100);
DISPLAY INVISIBLE (-2125 4100);
FORCEPROP 1 LASTPIN (-2100 4025) $PN 1
J 0
(-2088 4037);
DISPLAY 0.787234 (-2088 4037);
PAINT MONO (-2088 4037);
FORCEPROP 1 LASTPIN (-1900 4025) $PN 2
J 0
(-1938 4037);
DISPLAY 0.787234 (-1938 4037);
PAINT MONO (-1938 4037);
FORCEPROP 1 LAST MATERIAL CHIP
J 0
(-2275 4075);
DISPLAY 0.510638 (-2275 4075);
FORCEPROP 1 LAST PACK_TYPE 0402LF
J 0
(-2325 4025);
DISPLAY 0.510638 (-2325 4025);
FORCEPROP 1 LAST WATTAGE 1/16W
J 2
(-1575 4025);
DISPLAY 0.510638 (-1575 4025);
FORCEPROP 1 LAST TOLERANCE 5%
J 0
(-1825 4025);
DISPLAY 0.510638 (-1825 4025);
FORCEPROP 1 LAST VALUE 0
J 2
(-1875 4025);
DISPLAY 0.510638 (-1875 4025);
FORCEPROP 2 LAST CDS_LIB pure_quanta
J 0
(-2000 4025);
DISPLAY INVISIBLE (-2000 4025);
FORCEPROP 1 LAST PATH I327
J 0
(-2050 4175);
DISPLAY 0.978723 (-2050 4175);
PAINT WHITE (-2050 4175);
DISPLAY INVISIBLE (-2050 4175);
FORCEPROP 1 LAST PART_NUMBER CS00002JB13
J 0
(-2125 4075);
DISPLAY 0.510638 (-2125 4075);
DISPLAY INVISIBLE (-2125 4075);
FORCEADD UNIVERSAL_GND..1
(-9100 275);
FORCEPROP 3 LASTPIN (-9100 325) SIG_NAME GND\g
J 0
(-9090 335);
DISPLAY 0.659574 (-9090 335);
PAINT MONO (-9090 335);
DISPLAY INVISIBLE (-9090 335);
FORCEPROP 2 LAST CDS_LIB pure_quanta_power
J 0
(-9100 275);
DISPLAY INVISIBLE (-9100 275);
FORCEPROP 1 LAST HDL_POWER GND
J 1
(-9075 200);
DISPLAY 0.872340 (-9075 200);
PAINT GREEN (-9075 200);
DISPLAY INVISIBLE (-9075 200);
FORCEPROP 1 LAST PATH I328
J 0
(-9025 275);
DISPLAY 0.872340 (-9025 275);
PAINT AQUA (-9025 275);
DISPLAY INVISIBLE (-9025 275);
FORCEADD UNIVERSAL_GND..1
(-8975 275);
FORCEPROP 3 LASTPIN (-8975 325) SIG_NAME GND\g
J 0
(-8965 335);
DISPLAY 0.659574 (-8965 335);
PAINT MONO (-8965 335);
DISPLAY INVISIBLE (-8965 335);
FORCEPROP 2 LAST CDS_LIB pure_quanta_power
J 0
(-8975 275);
DISPLAY INVISIBLE (-8975 275);
FORCEPROP 1 LAST HDL_POWER GND
J 1
(-8950 200);
DISPLAY 0.872340 (-8950 200);
PAINT GREEN (-8950 200);
DISPLAY INVISIBLE (-8950 200);
FORCEPROP 1 LAST PATH I329
J 0
(-8900 275);
DISPLAY 0.872340 (-8900 275);
PAINT AQUA (-8900 275);
DISPLAY INVISIBLE (-8900 275);
FORCEADD Q_RES..1
R 1
(-9100 425);
FORCEPROP 1 LAST LOCATION R5032
J 0
(-9075 350);
DISPLAY 0.489362 (-9075 350);
PAINT SKYBLUE (-9075 350);
FORCEPROP 2 LAST $SEC 1
J 0
(-9075 475);
DISPLAY 0.680851 (-9075 475);
PAINT MONO (-9075 475);
DISPLAY INVISIBLE (-9075 475);
FORCEPROP 2 LAST CDS_SEC 1
J 0
(-9075 475);
DISPLAY 1.021277 (-9075 475);
DISPLAY INVISIBLE (-9075 475);
FORCEPROP 1 LASTPIN (-9100 325) $PN 1
R 1
J 0
(-9112 337);
DISPLAY 0.489362 (-9112 337);
PAINT MONO (-9112 337);
FORCEPROP 1 LASTPIN (-9100 525) $PN 2
R 1
J 0
(-9112 487);
DISPLAY 0.489362 (-9112 487);
PAINT MONO (-9112 487);
FORCEPROP 1 LAST MATERIAL EMPTY
J 0
(-9075 450);
DISPLAY 0.489362 (-9075 450);
PAINT RED (-9075 450);
FORCEPROP 1 LAST VALUE 4.7K
J 0
(-9075 400);
DISPLAY 0.489362 (-9075 400);
PAINT SKYBLUE (-9075 400);
FORCEPROP 1 LAST PACK_TYPE 0402LF
R 1
J 0
(-8950 675);
DISPLAY 0.978723 (-8950 675);
PAINT SKYBLUE (-8950 675);
DISPLAY INVISIBLE (-8950 675);
FORCEPROP 1 LAST TOLERANCE 5%
R 1
J 0
(-9000 425);
DISPLAY 0.978723 (-9000 425);
PAINT SKYBLUE (-9000 425);
DISPLAY INVISIBLE (-9000 425);
FORCEPROP 1 LAST WATTAGE 1/16W
R 1
J 2
(-8950 400);
DISPLAY 0.978723 (-8950 400);
PAINT SKYBLUE (-8950 400);
DISPLAY INVISIBLE (-8950 400);
FORCEPROP 2 LAST CDS_LIB pure_quanta
J 0
(-9100 425);
DISPLAY INVISIBLE (-9100 425);
FORCEPROP 1 LAST PATH I330
R 1
J 0
(-9250 375);
DISPLAY 0.978723 (-9250 375);
PAINT WHITE (-9250 375);
DISPLAY INVISIBLE (-9250 375);
FORCEPROP 1 LAST PART_NUMBER CS24702JB10
R 1
J 0
(-9200 375);
DISPLAY 0.978723 (-9200 375);
PAINT SKYBLUE (-9200 375);
DISPLAY INVISIBLE (-9200 375);
FORCEADD Q_RES..1
R 1
(-8975 425);
FORCEPROP 1 LAST LOCATION R5031
J 0
(-8950 350);
DISPLAY 0.489362 (-8950 350);
PAINT SKYBLUE (-8950 350);
FORCEPROP 2 LAST $SEC 1
J 0
(-8950 475);
DISPLAY 0.680851 (-8950 475);
PAINT MONO (-8950 475);
DISPLAY INVISIBLE (-8950 475);
FORCEPROP 2 LAST CDS_SEC 1
J 0
(-8950 475);
DISPLAY 1.021277 (-8950 475);
DISPLAY INVISIBLE (-8950 475);
FORCEPROP 1 LASTPIN (-8975 325) $PN 1
R 1
J 0
(-8987 337);
DISPLAY 0.489362 (-8987 337);
PAINT MONO (-8987 337);
FORCEPROP 1 LASTPIN (-8975 525) $PN 2
R 1
J 0
(-8987 487);
DISPLAY 0.489362 (-8987 487);
PAINT MONO (-8987 487);
FORCEPROP 1 LAST MATERIAL EMPTY
J 0
(-8950 450);
DISPLAY 0.489362 (-8950 450);
PAINT RED (-8950 450);
FORCEPROP 1 LAST VALUE 4.7K
J 0
(-8950 400);
DISPLAY 0.489362 (-8950 400);
PAINT SKYBLUE (-8950 400);
FORCEPROP 1 LAST PACK_TYPE 0402LF
R 1
J 0
(-8825 675);
DISPLAY 0.978723 (-8825 675);
PAINT SKYBLUE (-8825 675);
DISPLAY INVISIBLE (-8825 675);
FORCEPROP 1 LAST TOLERANCE 5%
R 1
J 0
(-8875 425);
DISPLAY 0.978723 (-8875 425);
PAINT SKYBLUE (-8875 425);
DISPLAY INVISIBLE (-8875 425);
FORCEPROP 1 LAST WATTAGE 1/16W
R 1
J 2
(-8825 400);
DISPLAY 0.978723 (-8825 400);
PAINT SKYBLUE (-8825 400);
DISPLAY INVISIBLE (-8825 400);
FORCEPROP 2 LAST CDS_LIB pure_quanta
J 0
(-8975 425);
DISPLAY INVISIBLE (-8975 425);
FORCEPROP 1 LAST PATH I331
R 1
J 0
(-9125 375);
DISPLAY 0.978723 (-9125 375);
PAINT WHITE (-9125 375);
DISPLAY INVISIBLE (-9125 375);
FORCEPROP 1 LAST PART_NUMBER CS24702JB10
R 1
J 0
(-9075 375);
DISPLAY 0.978723 (-9075 375);
PAINT SKYBLUE (-9075 375);
DISPLAY INVISIBLE (-9075 375);
FORCEADD UNIVERSAL_GND..1
(-8850 275);
FORCEPROP 3 LASTPIN (-8850 325) SIG_NAME GND\g
J 0
(-8840 335);
DISPLAY 0.659574 (-8840 335);
PAINT MONO (-8840 335);
DISPLAY INVISIBLE (-8840 335);
FORCEPROP 2 LAST CDS_LIB pure_quanta_power
J 0
(-8850 275);
DISPLAY INVISIBLE (-8850 275);
FORCEPROP 1 LAST HDL_POWER GND
J 1
(-8825 200);
DISPLAY 0.872340 (-8825 200);
PAINT GREEN (-8825 200);
DISPLAY INVISIBLE (-8825 200);
FORCEPROP 1 LAST PATH I332
J 0
(-8775 275);
DISPLAY 0.872340 (-8775 275);
PAINT AQUA (-8775 275);
DISPLAY INVISIBLE (-8775 275);
FORCEADD UNIVERSAL_GND..1
(-8700 275);
FORCEPROP 3 LASTPIN (-8700 325) SIG_NAME GND\g
J 0
(-8690 335);
DISPLAY 0.659574 (-8690 335);
PAINT MONO (-8690 335);
DISPLAY INVISIBLE (-8690 335);
FORCEPROP 2 LAST CDS_LIB pure_quanta_power
J 0
(-8700 275);
DISPLAY INVISIBLE (-8700 275);
FORCEPROP 1 LAST HDL_POWER GND
J 1
(-8675 200);
DISPLAY 0.872340 (-8675 200);
PAINT GREEN (-8675 200);
DISPLAY INVISIBLE (-8675 200);
FORCEPROP 1 LAST PATH I333
J 0
(-8625 275);
DISPLAY 0.872340 (-8625 275);
PAINT AQUA (-8625 275);
DISPLAY INVISIBLE (-8625 275);
FORCEADD Q_RES..1
R 1
(-8850 425);
FORCEPROP 1 LAST LOCATION R5030
J 0
(-8825 350);
DISPLAY 0.489362 (-8825 350);
PAINT SKYBLUE (-8825 350);
FORCEPROP 2 LAST $SEC 1
J 0
(-8825 475);
DISPLAY 0.680851 (-8825 475);
PAINT MONO (-8825 475);
DISPLAY INVISIBLE (-8825 475);
FORCEPROP 2 LAST CDS_SEC 1
J 0
(-8825 475);
DISPLAY 1.021277 (-8825 475);
DISPLAY INVISIBLE (-8825 475);
FORCEPROP 1 LASTPIN (-8850 325) $PN 1
R 1
J 0
(-8862 337);
DISPLAY 0.489362 (-8862 337);
PAINT MONO (-8862 337);
FORCEPROP 1 LASTPIN (-8850 525) $PN 2
R 1
J 0
(-8862 487);
DISPLAY 0.489362 (-8862 487);
PAINT MONO (-8862 487);
FORCEPROP 1 LAST MATERIAL EMPTY
J 0
(-8825 450);
DISPLAY 0.489362 (-8825 450);
PAINT RED (-8825 450);
FORCEPROP 1 LAST VALUE 4.7K
J 0
(-8825 400);
DISPLAY 0.489362 (-8825 400);
PAINT SKYBLUE (-8825 400);
FORCEPROP 1 LAST PACK_TYPE 0402LF
R 1
J 0
(-8700 675);
DISPLAY 0.978723 (-8700 675);
PAINT SKYBLUE (-8700 675);
DISPLAY INVISIBLE (-8700 675);
FORCEPROP 1 LAST TOLERANCE 5%
R 1
J 0
(-8750 425);
DISPLAY 0.978723 (-8750 425);
PAINT SKYBLUE (-8750 425);
DISPLAY INVISIBLE (-8750 425);
FORCEPROP 1 LAST WATTAGE 1/16W
R 1
J 2
(-8700 400);
DISPLAY 0.978723 (-8700 400);
PAINT SKYBLUE (-8700 400);
DISPLAY INVISIBLE (-8700 400);
FORCEPROP 2 LAST CDS_LIB pure_quanta
J 0
(-8850 425);
DISPLAY INVISIBLE (-8850 425);
FORCEPROP 1 LAST PATH I334
R 1
J 0
(-9000 375);
DISPLAY 0.978723 (-9000 375);
PAINT WHITE (-9000 375);
DISPLAY INVISIBLE (-9000 375);
FORCEPROP 1 LAST PART_NUMBER CS24702JB10
R 1
J 0
(-8950 375);
DISPLAY 0.978723 (-8950 375);
PAINT SKYBLUE (-8950 375);
DISPLAY INVISIBLE (-8950 375);
FORCEADD Q_RES..1
R 1
(-8700 425);
FORCEPROP 1 LAST LOCATION R491
J 0
(-8675 350);
DISPLAY 0.489362 (-8675 350);
PAINT SKYBLUE (-8675 350);
FORCEPROP 2 LAST $SEC 1
J 0
(-8675 475);
DISPLAY 0.680851 (-8675 475);
PAINT MONO (-8675 475);
DISPLAY INVISIBLE (-8675 475);
FORCEPROP 2 LAST CDS_SEC 1
J 0
(-8675 475);
DISPLAY 1.021277 (-8675 475);
DISPLAY INVISIBLE (-8675 475);
FORCEPROP 1 LASTPIN (-8700 325) $PN 1
R 1
J 0
(-8712 337);
DISPLAY 0.489362 (-8712 337);
PAINT MONO (-8712 337);
FORCEPROP 1 LASTPIN (-8700 525) $PN 2
R 1
J 0
(-8712 487);
DISPLAY 0.489362 (-8712 487);
PAINT MONO (-8712 487);
FORCEPROP 1 LAST VALUE 4.7K
J 0
(-8675 400);
DISPLAY 0.489362 (-8675 400);
PAINT SKYBLUE (-8675 400);
FORCEPROP 1 LAST MATERIAL EMPTY
J 0
(-8675 450);
DISPLAY 0.489362 (-8675 450);
PAINT RED (-8675 450);
FORCEPROP 1 LAST PACK_TYPE 0402LF
R 1
J 0
(-8550 675);
DISPLAY 0.978723 (-8550 675);
PAINT SKYBLUE (-8550 675);
DISPLAY INVISIBLE (-8550 675);
FORCEPROP 1 LAST TOLERANCE 5%
R 1
J 0
(-8600 425);
DISPLAY 0.978723 (-8600 425);
PAINT SKYBLUE (-8600 425);
DISPLAY INVISIBLE (-8600 425);
FORCEPROP 1 LAST WATTAGE 1/16W
R 1
J 2
(-8550 400);
DISPLAY 0.978723 (-8550 400);
PAINT SKYBLUE (-8550 400);
DISPLAY INVISIBLE (-8550 400);
FORCEPROP 2 LAST CDS_LIB pure_quanta
J 0
(-8700 425);
DISPLAY INVISIBLE (-8700 425);
FORCEPROP 1 LAST PATH I335
R 1
J 0
(-8850 375);
DISPLAY 0.978723 (-8850 375);
PAINT WHITE (-8850 375);
DISPLAY INVISIBLE (-8850 375);
FORCEPROP 1 LAST PART_NUMBER CS24702JB10
R 1
J 0
(-8800 375);
DISPLAY 0.978723 (-8800 375);
PAINT SKYBLUE (-8800 375);
DISPLAY INVISIBLE (-8800 375);
FORCEADD Q_RES..1
R 1
(-9100 1150);
FORCEPROP 1 LAST LOCATION R544
J 0
(-9075 1075);
DISPLAY 0.489362 (-9075 1075);
PAINT SKYBLUE (-9075 1075);
FORCEPROP 2 LAST $SEC 1
J 0
(-9075 1200);
DISPLAY 0.680851 (-9075 1200);
PAINT MONO (-9075 1200);
DISPLAY INVISIBLE (-9075 1200);
FORCEPROP 2 LAST CDS_SEC 1
J 0
(-9075 1200);
DISPLAY 1.021277 (-9075 1200);
DISPLAY INVISIBLE (-9075 1200);
FORCEPROP 1 LASTPIN (-9100 1050) $PN 1
R 1
J 0
(-9112 1062);
DISPLAY 0.489362 (-9112 1062);
PAINT MONO (-9112 1062);
FORCEPROP 1 LASTPIN (-9100 1250) $PN 2
R 1
J 0
(-9112 1212);
DISPLAY 0.489362 (-9112 1212);
PAINT MONO (-9112 1212);
FORCEPROP 1 LAST MATERIAL CHIP
J 0
(-9075 1175);
DISPLAY 0.489362 (-9075 1175);
PAINT RED (-9075 1175);
FORCEPROP 1 LAST VALUE 4.7K
J 0
(-9075 1125);
DISPLAY 0.489362 (-9075 1125);
PAINT SKYBLUE (-9075 1125);
FORCEPROP 1 LAST PACK_TYPE 0402LF
R 1
J 0
(-8950 1400);
DISPLAY 0.978723 (-8950 1400);
PAINT SKYBLUE (-8950 1400);
DISPLAY INVISIBLE (-8950 1400);
FORCEPROP 1 LAST TOLERANCE 5%
R 1
J 0
(-9000 1150);
DISPLAY 0.978723 (-9000 1150);
PAINT SKYBLUE (-9000 1150);
DISPLAY INVISIBLE (-9000 1150);
FORCEPROP 1 LAST WATTAGE 1/16W
R 1
J 2
(-8950 1125);
DISPLAY 0.978723 (-8950 1125);
PAINT SKYBLUE (-8950 1125);
DISPLAY INVISIBLE (-8950 1125);
FORCEPROP 2 LAST CDS_LIB pure_quanta
J 0
(-9100 1150);
DISPLAY INVISIBLE (-9100 1150);
FORCEPROP 1 LAST PATH I336
R 1
J 0
(-9250 1100);
DISPLAY 0.978723 (-9250 1100);
PAINT WHITE (-9250 1100);
DISPLAY INVISIBLE (-9250 1100);
FORCEPROP 1 LAST PART_NUMBER CS24702JB10
R 1
J 0
(-9200 1100);
DISPLAY 0.978723 (-9200 1100);
PAINT SKYBLUE (-9200 1100);
DISPLAY INVISIBLE (-9200 1100);
FORCEADD Q_RES..1
R 1
(-8975 1150);
FORCEPROP 1 LAST LOCATION R545
J 0
(-8950 1075);
DISPLAY 0.489362 (-8950 1075);
PAINT SKYBLUE (-8950 1075);
FORCEPROP 2 LAST $SEC 1
J 0
(-8950 1200);
DISPLAY 0.680851 (-8950 1200);
PAINT MONO (-8950 1200);
DISPLAY INVISIBLE (-8950 1200);
FORCEPROP 2 LAST CDS_SEC 1
J 0
(-8950 1200);
DISPLAY 1.021277 (-8950 1200);
DISPLAY INVISIBLE (-8950 1200);
FORCEPROP 1 LASTPIN (-8975 1050) $PN 1
R 1
J 0
(-8987 1062);
DISPLAY 0.489362 (-8987 1062);
PAINT MONO (-8987 1062);
FORCEPROP 1 LASTPIN (-8975 1250) $PN 2
R 1
J 0
(-8987 1212);
DISPLAY 0.489362 (-8987 1212);
PAINT MONO (-8987 1212);
FORCEPROP 1 LAST VALUE 4.7K
J 0
(-8950 1125);
DISPLAY 0.489362 (-8950 1125);
PAINT SKYBLUE (-8950 1125);
FORCEPROP 1 LAST MATERIAL CHIP
J 0
(-8950 1175);
DISPLAY 0.489362 (-8950 1175);
PAINT RED (-8950 1175);
FORCEPROP 1 LAST PACK_TYPE 0402LF
R 1
J 0
(-8825 1400);
DISPLAY 0.978723 (-8825 1400);
PAINT SKYBLUE (-8825 1400);
DISPLAY INVISIBLE (-8825 1400);
FORCEPROP 1 LAST TOLERANCE 5%
R 1
J 0
(-8875 1150);
DISPLAY 0.978723 (-8875 1150);
PAINT SKYBLUE (-8875 1150);
DISPLAY INVISIBLE (-8875 1150);
FORCEPROP 1 LAST WATTAGE 1/16W
R 1
J 2
(-8825 1125);
DISPLAY 0.978723 (-8825 1125);
PAINT SKYBLUE (-8825 1125);
DISPLAY INVISIBLE (-8825 1125);
FORCEPROP 2 LAST CDS_LIB pure_quanta
J 0
(-8975 1150);
DISPLAY INVISIBLE (-8975 1150);
FORCEPROP 1 LAST PATH I337
R 1
J 0
(-9125 1100);
DISPLAY 0.978723 (-9125 1100);
PAINT WHITE (-9125 1100);
DISPLAY INVISIBLE (-9125 1100);
FORCEPROP 1 LAST PART_NUMBER CS24702JB10
R 1
J 0
(-9075 1100);
DISPLAY 0.978723 (-9075 1100);
PAINT SKYBLUE (-9075 1100);
DISPLAY INVISIBLE (-9075 1100);
FORCEADD Q_RES..1
R 1
(-8850 1150);
FORCEPROP 1 LAST LOCATION R546
J 0
(-8825 1075);
DISPLAY 0.489362 (-8825 1075);
PAINT SKYBLUE (-8825 1075);
FORCEPROP 2 LAST $SEC 1
J 0
(-8825 1200);
DISPLAY 0.680851 (-8825 1200);
PAINT MONO (-8825 1200);
DISPLAY INVISIBLE (-8825 1200);
FORCEPROP 2 LAST CDS_SEC 1
J 0
(-8825 1200);
DISPLAY 1.021277 (-8825 1200);
DISPLAY INVISIBLE (-8825 1200);
FORCEPROP 1 LASTPIN (-8850 1050) $PN 1
R 1
J 0
(-8862 1062);
DISPLAY 0.489362 (-8862 1062);
PAINT MONO (-8862 1062);
FORCEPROP 1 LASTPIN (-8850 1250) $PN 2
R 1
J 0
(-8862 1212);
DISPLAY 0.489362 (-8862 1212);
PAINT MONO (-8862 1212);
FORCEPROP 1 LAST VALUE 4.7K
J 0
(-8825 1125);
DISPLAY 0.489362 (-8825 1125);
PAINT SKYBLUE (-8825 1125);
FORCEPROP 1 LAST MATERIAL CHIP
J 0
(-8825 1175);
DISPLAY 0.489362 (-8825 1175);
PAINT RED (-8825 1175);
FORCEPROP 1 LAST PACK_TYPE 0402LF
R 1
J 0
(-8700 1400);
DISPLAY 0.978723 (-8700 1400);
PAINT SKYBLUE (-8700 1400);
DISPLAY INVISIBLE (-8700 1400);
FORCEPROP 1 LAST TOLERANCE 5%
R 1
J 0
(-8750 1150);
DISPLAY 0.978723 (-8750 1150);
PAINT SKYBLUE (-8750 1150);
DISPLAY INVISIBLE (-8750 1150);
FORCEPROP 1 LAST WATTAGE 1/16W
R 1
J 2
(-8700 1125);
DISPLAY 0.978723 (-8700 1125);
PAINT SKYBLUE (-8700 1125);
DISPLAY INVISIBLE (-8700 1125);
FORCEPROP 2 LAST CDS_LIB pure_quanta
J 0
(-8850 1150);
DISPLAY INVISIBLE (-8850 1150);
FORCEPROP 1 LAST PATH I338
R 1
J 0
(-9000 1100);
DISPLAY 0.978723 (-9000 1100);
PAINT WHITE (-9000 1100);
DISPLAY INVISIBLE (-9000 1100);
FORCEPROP 1 LAST PART_NUMBER CS24702JB10
R 1
J 0
(-8950 1100);
DISPLAY 0.978723 (-8950 1100);
PAINT SKYBLUE (-8950 1100);
DISPLAY INVISIBLE (-8950 1100);
FORCEADD Q_RES..1
R 1
(-8700 1150);
FORCEPROP 1 LAST LOCATION R456
J 0
(-8675 1075);
DISPLAY 0.489362 (-8675 1075);
PAINT SKYBLUE (-8675 1075);
FORCEPROP 2 LAST $SEC 1
J 0
(-8675 1200);
DISPLAY 0.680851 (-8675 1200);
PAINT MONO (-8675 1200);
DISPLAY INVISIBLE (-8675 1200);
FORCEPROP 2 LAST CDS_SEC 1
J 0
(-8675 1200);
DISPLAY 1.021277 (-8675 1200);
DISPLAY INVISIBLE (-8675 1200);
FORCEPROP 1 LASTPIN (-8700 1050) $PN 1
R 1
J 0
(-8712 1062);
DISPLAY 0.489362 (-8712 1062);
PAINT MONO (-8712 1062);
FORCEPROP 1 LASTPIN (-8700 1250) $PN 2
R 1
J 0
(-8712 1212);
DISPLAY 0.489362 (-8712 1212);
PAINT MONO (-8712 1212);
FORCEPROP 1 LAST MATERIAL EMPTY
J 0
(-8675 1175);
DISPLAY 0.489362 (-8675 1175);
PAINT RED (-8675 1175);
FORCEPROP 1 LAST VALUE 4.7K
J 0
(-8675 1125);
DISPLAY 0.489362 (-8675 1125);
PAINT SKYBLUE (-8675 1125);
FORCEPROP 2 LAST CDS_LIB pure_quanta
J 0
(-8700 1150);
DISPLAY INVISIBLE (-8700 1150);
FORCEPROP 1 LAST WATTAGE 1/16W
R 1
J 2
(-8550 1125);
DISPLAY 0.978723 (-8550 1125);
PAINT SKYBLUE (-8550 1125);
DISPLAY INVISIBLE (-8550 1125);
FORCEPROP 1 LAST TOLERANCE 5%
R 1
J 0
(-8600 1150);
DISPLAY 0.978723 (-8600 1150);
PAINT SKYBLUE (-8600 1150);
DISPLAY INVISIBLE (-8600 1150);
FORCEPROP 1 LAST PACK_TYPE 0402LF
R 1
J 0
(-8550 1400);
DISPLAY 0.978723 (-8550 1400);
PAINT SKYBLUE (-8550 1400);
DISPLAY INVISIBLE (-8550 1400);
FORCEPROP 1 LAST PATH I339
R 1
J 0
(-8850 1100);
DISPLAY 0.978723 (-8850 1100);
PAINT WHITE (-8850 1100);
DISPLAY INVISIBLE (-8850 1100);
FORCEPROP 1 LAST PART_NUMBER CS24702JB10
R 1
J 0
(-8800 1100);
DISPLAY 0.978723 (-8800 1100);
PAINT SKYBLUE (-8800 1100);
DISPLAY INVISIBLE (-8800 1100);
FORCEADD UNIVERSAL_GND..1
(-8475 275);
FORCEPROP 3 LASTPIN (-8475 325) SIG_NAME GND\g
J 0
(-8465 335);
DISPLAY 0.659574 (-8465 335);
PAINT MONO (-8465 335);
DISPLAY INVISIBLE (-8465 335);
FORCEPROP 2 LAST CDS_LIB pure_quanta_power
J 0
(-8475 275);
DISPLAY INVISIBLE (-8475 275);
FORCEPROP 1 LAST HDL_POWER GND
J 1
(-8450 200);
DISPLAY 0.872340 (-8450 200);
PAINT GREEN (-8450 200);
DISPLAY INVISIBLE (-8450 200);
FORCEPROP 1 LAST PATH I340
J 0
(-8400 275);
DISPLAY 0.872340 (-8400 275);
PAINT AQUA (-8400 275);
DISPLAY INVISIBLE (-8400 275);
FORCEADD Q_RES..1
R 1
(-8475 425);
FORCEPROP 1 LAST LOCATION R584
J 0
(-8450 325);
DISPLAY 0.489362 (-8450 325);
PAINT SKYBLUE (-8450 325);
FORCEPROP 0 LAST $SEC 1
R 1
J 0
(-8450 475);
DISPLAY 0.680851 (-8450 475);
PAINT MONO (-8450 475);
DISPLAY INVISIBLE (-8450 475);
FORCEPROP 0 LAST CDS_SEC 1
R 1
J 0
(-8450 475);
DISPLAY 1.021277 (-8450 475);
DISPLAY INVISIBLE (-8450 475);
FORCEPROP 1 LASTPIN (-8475 325) $PN 1
R 1
J 0
(-8487 337);
DISPLAY 0.489362 (-8487 337);
PAINT MONO (-8487 337);
FORCEPROP 1 LASTPIN (-8475 525) $PN 2
R 1
J 0
(-8487 487);
DISPLAY 0.489362 (-8487 487);
PAINT MONO (-8487 487);
FORCEPROP 1 LAST MATERIAL EMPTY
J 0
(-8450 450);
DISPLAY 0.489362 (-8450 450);
PAINT RED (-8450 450);
FORCEPROP 1 LAST VALUE 4.7K
J 0
(-8450 400);
DISPLAY 0.489362 (-8450 400);
PAINT SKYBLUE (-8450 400);
FORCEPROP 2 LAST CDS_LIB pure_quanta
J 0
(-8475 425);
DISPLAY INVISIBLE (-8475 425);
FORCEPROP 1 LAST WATTAGE 1/16W
R 1
J 2
(-8325 400);
DISPLAY 0.978723 (-8325 400);
PAINT SKYBLUE (-8325 400);
DISPLAY INVISIBLE (-8325 400);
FORCEPROP 1 LAST TOLERANCE 5%
R 1
J 0
(-8375 425);
DISPLAY 0.978723 (-8375 425);
PAINT SKYBLUE (-8375 425);
DISPLAY INVISIBLE (-8375 425);
FORCEPROP 1 LAST PACK_TYPE 0402LF
R 1
J 0
(-8325 675);
DISPLAY 0.978723 (-8325 675);
PAINT SKYBLUE (-8325 675);
DISPLAY INVISIBLE (-8325 675);
FORCEPROP 1 LAST PATH I341
R 1
J 0
(-8625 375);
DISPLAY 0.978723 (-8625 375);
PAINT WHITE (-8625 375);
DISPLAY INVISIBLE (-8625 375);
FORCEPROP 1 LAST PART_NUMBER CS24702JB10
R 1
J 0
(-8575 375);
DISPLAY 0.978723 (-8575 375);
PAINT SKYBLUE (-8575 375);
DISPLAY INVISIBLE (-8575 375);
FORCEADD Q_RES..1
R 1
(-8475 1150);
FORCEPROP 1 LAST LOCATION R583
J 0
(-8450 1050);
DISPLAY 0.489362 (-8450 1050);
PAINT SKYBLUE (-8450 1050);
FORCEPROP 0 LAST $SEC 1
R 1
J 0
(-8450 1200);
DISPLAY 0.680851 (-8450 1200);
PAINT MONO (-8450 1200);
DISPLAY INVISIBLE (-8450 1200);
FORCEPROP 0 LAST CDS_SEC 1
R 1
J 0
(-8450 1200);
DISPLAY 1.021277 (-8450 1200);
DISPLAY INVISIBLE (-8450 1200);
FORCEPROP 1 LASTPIN (-8475 1050) $PN 1
R 1
J 0
(-8485 1060);
DISPLAY 0.489362 (-8485 1060);
PAINT MONO (-8485 1060);
FORCEPROP 1 LASTPIN (-8475 1250) $PN 2
R 1
J 0
(-8487 1212);
DISPLAY 0.489362 (-8487 1212);
PAINT MONO (-8487 1212);
FORCEPROP 1 LAST VALUE 4.7K
J 0
(-8450 1125);
DISPLAY 0.489362 (-8450 1125);
PAINT SKYBLUE (-8450 1125);
FORCEPROP 1 LAST MATERIAL EMPTY
J 0
(-8450 1175);
DISPLAY 0.489362 (-8450 1175);
PAINT RED (-8450 1175);
FORCEPROP 2 LAST CDS_LIB pure_quanta
J 0
(-8475 1150);
DISPLAY INVISIBLE (-8475 1150);
FORCEPROP 1 LAST WATTAGE 1/16W
R 1
J 2
(-8325 1125);
DISPLAY 0.978723 (-8325 1125);
PAINT SKYBLUE (-8325 1125);
DISPLAY INVISIBLE (-8325 1125);
FORCEPROP 1 LAST TOLERANCE 5%
R 1
J 0
(-8375 1150);
DISPLAY 0.978723 (-8375 1150);
PAINT SKYBLUE (-8375 1150);
DISPLAY INVISIBLE (-8375 1150);
FORCEPROP 1 LAST PACK_TYPE 0402LF
R 1
J 0
(-8325 1400);
DISPLAY 0.978723 (-8325 1400);
PAINT SKYBLUE (-8325 1400);
DISPLAY INVISIBLE (-8325 1400);
FORCEPROP 1 LAST PATH I342
R 1
J 0
(-8625 1100);
DISPLAY 0.978723 (-8625 1100);
PAINT WHITE (-8625 1100);
DISPLAY INVISIBLE (-8625 1100);
FORCEPROP 1 LAST PART_NUMBER CS24702JB10
R 1
J 0
(-8575 1100);
DISPLAY 0.978723 (-8575 1100);
PAINT SKYBLUE (-8575 1100);
DISPLAY INVISIBLE (-8575 1100);
FORCEADD UNIVERSAL_POWER..1
(-8700 1350);
FORCEPROP 3 LASTPIN (-8700 1300) SIG_NAME PVDD18_S5_P1\g
J 0
(-8690 1310);
DISPLAY 0.659574 (-8690 1310);
PAINT MONO (-8690 1310);
DISPLAY INVISIBLE (-8690 1310);
FORCEPROP 1 LAST HDL_POWER PVDD18_S5_P1
J 1
(-8700 1400);
DISPLAY 0.489362 (-8700 1400);
PAINT GREEN (-8700 1400);
FORCEPROP 2 LAST CDS_LIB pure_quanta_power
J 0
(-8700 1350);
DISPLAY INVISIBLE (-8700 1350);
FORCEPROP 1 LAST PATH I343
J 0
(-8650 1375);
DISPLAY 0.872340 (-8650 1375);
PAINT AQUA (-8650 1375);
DISPLAY INVISIBLE (-8650 1375);
FORCEADD OFFPAGE..2
(-7625 675);
FORCEPROP 2 LAST $XR1 55 
J 0
(-7346 675);
DISPLAY 0.638298 (-7346 675);
PAINT MONO (-7346 675);
FORCEPROP 2 LAST $XR0 81 
J 0
(-7436 675);
DISPLAY 0.638298 (-7436 675);
PAINT MONO (-7436 675);
FORCEPROP 2 LAST CDS_LIB standard
J 0
(-7625 675);
DISPLAY INVISIBLE (-7625 675);
FORCEPROP 1 LAST OFFPAGE TRUE
J 0
(-7300 550);
DISPLAY 0.872340 (-7300 550);
PAINT GREEN (-7300 550);
DISPLAY INVISIBLE (-7300 550);
FORCEPROP 1 LAST COMMENT_BODY TRUE
J 0
(-7670 580);
DISPLAY 0.872340 (-7670 580);
PAINT GREEN (-7670 580);
DISPLAY INVISIBLE (-7670 580);
FORCEPROP 2 LAST PATH I344
J 0
(-7325 725);
DISPLAY 0.680851 (-7325 725);
DISPLAY INVISIBLE (-7325 725);
FORCEADD OFFPAGE..2
(-7625 750);
FORCEPROP 2 LAST $XR1 81 
J 0
(-7346 750);
DISPLAY 0.638298 (-7346 750);
PAINT MONO (-7346 750);
FORCEPROP 2 LAST $XR0 55 
J 0
(-7436 750);
DISPLAY 0.638298 (-7436 750);
PAINT MONO (-7436 750);
FORCEPROP 2 LAST CDS_LIB standard
J 2
(-7625 750);
DISPLAY INVISIBLE (-7625 750);
FORCEPROP 1 LAST OFFPAGE TRUE
J 0
(-7300 625);
DISPLAY 0.872340 (-7300 625);
PAINT GREEN (-7300 625);
DISPLAY INVISIBLE (-7300 625);
FORCEPROP 1 LAST COMMENT_BODY TRUE
J 0
(-7670 655);
DISPLAY 0.872340 (-7670 655);
PAINT GREEN (-7670 655);
DISPLAY INVISIBLE (-7670 655);
FORCEPROP 2 LAST PATH I345
J 0
(-7325 800);
DISPLAY 0.680851 (-7325 800);
DISPLAY INVISIBLE (-7325 800);
FORCEADD OFFPAGE..2
(-7625 800);
FORCEPROP 2 LAST $XR1 55 
J 0
(-7346 800);
DISPLAY 0.638298 (-7346 800);
PAINT MONO (-7346 800);
FORCEPROP 2 LAST $XR0 82 
J 0
(-7436 800);
DISPLAY 0.638298 (-7436 800);
PAINT MONO (-7436 800);
FORCEPROP 2 LAST CDS_LIB standard
J 2
(-7625 800);
DISPLAY INVISIBLE (-7625 800);
FORCEPROP 1 LAST OFFPAGE TRUE
J 0
(-7300 675);
DISPLAY 0.872340 (-7300 675);
PAINT GREEN (-7300 675);
DISPLAY INVISIBLE (-7300 675);
FORCEPROP 1 LAST COMMENT_BODY TRUE
J 0
(-7670 705);
DISPLAY 0.872340 (-7670 705);
PAINT GREEN (-7670 705);
DISPLAY INVISIBLE (-7670 705);
FORCEPROP 2 LAST PATH I346
J 0
(-7450 875);
DISPLAY 0.680851 (-7450 875);
DISPLAY INVISIBLE (-7450 875);
FORCEADD OFFPAGE..2
(-7625 950);
FORCEPROP 2 LAST $XR1 55 
J 0
(-7346 950);
DISPLAY 0.638298 (-7346 950);
PAINT MONO (-7346 950);
FORCEPROP 2 LAST $XR0 82 
J 0
(-7436 950);
DISPLAY 0.638298 (-7436 950);
PAINT MONO (-7436 950);
FORCEPROP 2 LAST CDS_LIB standard
J 2
(-7625 950);
DISPLAY INVISIBLE (-7625 950);
FORCEPROP 1 LAST OFFPAGE TRUE
J 0
(-7300 825);
DISPLAY 0.872340 (-7300 825);
PAINT GREEN (-7300 825);
DISPLAY INVISIBLE (-7300 825);
FORCEPROP 1 LAST COMMENT_BODY TRUE
J 0
(-7670 855);
DISPLAY 0.872340 (-7670 855);
PAINT GREEN (-7670 855);
DISPLAY INVISIBLE (-7670 855);
FORCEPROP 2 LAST PATH I347
J 0
(-7450 1025);
DISPLAY 0.680851 (-7450 1025);
DISPLAY INVISIBLE (-7450 1025);
FORCEADD OFFPAGE..2
(-7625 875);
FORCEPROP 2 LAST $XR1 55 
J 0
(-7346 875);
DISPLAY 0.638298 (-7346 875);
PAINT MONO (-7346 875);
FORCEPROP 2 LAST $XR0 82 
J 0
(-7436 875);
DISPLAY 0.638298 (-7436 875);
PAINT MONO (-7436 875);
FORCEPROP 2 LAST CDS_LIB standard
J 2
(-7625 875);
DISPLAY INVISIBLE (-7625 875);
FORCEPROP 1 LAST OFFPAGE TRUE
J 0
(-7300 750);
DISPLAY 0.872340 (-7300 750);
PAINT GREEN (-7300 750);
DISPLAY INVISIBLE (-7300 750);
FORCEPROP 1 LAST COMMENT_BODY TRUE
J 0
(-7670 780);
DISPLAY 0.872340 (-7670 780);
PAINT GREEN (-7670 780);
DISPLAY INVISIBLE (-7670 780);
FORCEPROP 2 LAST PATH I348
J 0
(-7450 950);
DISPLAY 0.680851 (-7450 950);
DISPLAY INVISIBLE (-7450 950);
FORCEADD OFFPAGE..4
R 2
(-6650 3275);
FORCEPROP 2 LAST $XR1 82 
J 0
(-6961 3275);
DISPLAY 0.638298 (-6961 3275);
PAINT MONO (-6961 3275);
FORCEPROP 2 LAST $XR0 55 
J 0
(-6871 3275);
DISPLAY 0.638298 (-6871 3275);
PAINT MONO (-6871 3275);
FORCEPROP 2 LAST CDS_LIB standard
J 0
(-6650 3275);
DISPLAY INVISIBLE (-6650 3275);
FORCEPROP 1 LAST OFFPAGE TRUE
J 2
(-6975 3150);
DISPLAY 0.872340 (-6975 3150);
DISPLAY INVISIBLE (-6975 3150);
FORCEPROP 1 LAST COMMENT_BODY TRUE
J 2
(-6625 3175);
DISPLAY 0.872340 (-6625 3175);
PAINT GREEN (-6625 3175);
DISPLAY INVISIBLE (-6625 3175);
FORCEPROP 2 LAST PATH I349
J 0
(-6600 3350);
DISPLAY 0.680851 (-6600 3350);
DISPLAY INVISIBLE (-6600 3350);
FORCEADD OFFPAGE..4
R 2
(-6650 3325);
FORCEPROP 2 LAST $XR1 82 
J 0
(-6961 3325);
DISPLAY 0.638298 (-6961 3325);
PAINT MONO (-6961 3325);
FORCEPROP 2 LAST $XR0 55 
J 0
(-6871 3325);
DISPLAY 0.638298 (-6871 3325);
PAINT MONO (-6871 3325);
FORCEPROP 2 LAST CDS_LIB standard
J 0
(-6650 3325);
DISPLAY INVISIBLE (-6650 3325);
FORCEPROP 1 LAST OFFPAGE TRUE
J 2
(-6975 3200);
DISPLAY 0.872340 (-6975 3200);
DISPLAY INVISIBLE (-6975 3200);
FORCEPROP 1 LAST COMMENT_BODY TRUE
J 2
(-6625 3225);
DISPLAY 0.872340 (-6625 3225);
PAINT GREEN (-6625 3225);
DISPLAY INVISIBLE (-6625 3225);
FORCEPROP 2 LAST PATH I350
J 0
(-6600 3400);
DISPLAY 0.680851 (-6600 3400);
DISPLAY INVISIBLE (-6600 3400);
FORCEADD OFFPAGE..4
R 2
(-6650 3375);
FORCEPROP 2 LAST $XR1 82 
J 0
(-6961 3375);
DISPLAY 0.638298 (-6961 3375);
PAINT MONO (-6961 3375);
FORCEPROP 2 LAST $XR0 55 
J 0
(-6871 3375);
DISPLAY 0.638298 (-6871 3375);
PAINT MONO (-6871 3375);
FORCEPROP 2 LAST CDS_LIB standard
J 0
(-6650 3375);
DISPLAY INVISIBLE (-6650 3375);
FORCEPROP 1 LAST OFFPAGE TRUE
J 2
(-6975 3250);
DISPLAY 0.872340 (-6975 3250);
DISPLAY INVISIBLE (-6975 3250);
FORCEPROP 1 LAST COMMENT_BODY TRUE
J 2
(-6625 3275);
DISPLAY 0.872340 (-6625 3275);
PAINT GREEN (-6625 3275);
DISPLAY INVISIBLE (-6625 3275);
FORCEPROP 2 LAST PATH I351
J 0
(-6600 3450);
DISPLAY 0.680851 (-6600 3450);
DISPLAY INVISIBLE (-6600 3450);
FORCEADD Q_RES..1
R 2
(-8625 1700);
FORCEPROP 1 LAST LOCATION R548
J 0
(-8350 1700);
DISPLAY 0.489362 (-8350 1700);
PAINT SKYBLUE (-8350 1700);
FORCEPROP 0 LAST $SEC 1
J 2
(-8475 1750);
DISPLAY 0.680851 (-8475 1750);
PAINT MONO (-8475 1750);
DISPLAY INVISIBLE (-8475 1750);
FORCEPROP 0 LAST CDS_SEC 1
J 2
(-8475 1750);
DISPLAY 1.021277 (-8475 1750);
DISPLAY INVISIBLE (-8475 1750);
FORCEPROP 1 LASTPIN (-8525 1700) $PN 1
J 2
(-8537 1712);
DISPLAY 0.489362 (-8537 1712);
PAINT MONO (-8537 1712);
FORCEPROP 1 LASTPIN (-8725 1700) $PN 2
J 2
(-8687 1712);
DISPLAY 0.489362 (-8687 1712);
PAINT MONO (-8687 1712);
FORCEPROP 1 LAST VALUE 4.7K
J 0
(-8875 1700);
DISPLAY 0.489362 (-8875 1700);
PAINT SKYBLUE (-8875 1700);
FORCEPROP 1 LAST MATERIAL EMPTY
J 2
(-8375 1700);
DISPLAY 0.489362 (-8375 1700);
PAINT RED (-8375 1700);
FORCEPROP 1 LAST PACK_TYPE 0402LF
J 2
(-8875 1550);
DISPLAY 0.510638 (-8875 1550);
PAINT SKYBLUE (-8875 1550);
DISPLAY INVISIBLE (-8875 1550);
FORCEPROP 1 LAST TOLERANCE 5%
J 2
(-8750 1700);
DISPLAY 0.510638 (-8750 1700);
PAINT SKYBLUE (-8750 1700);
DISPLAY INVISIBLE (-8750 1700);
FORCEPROP 1 LAST WATTAGE 1/16W
J 0
(-8600 1550);
DISPLAY 0.510638 (-8600 1550);
PAINT SKYBLUE (-8600 1550);
DISPLAY INVISIBLE (-8600 1550);
FORCEPROP 2 LAST CDS_LIB pure_quanta
J 2
(-8625 1700);
DISPLAY INVISIBLE (-8625 1700);
FORCEPROP 1 LAST PATH I352
J 2
(-8575 1850);
DISPLAY 0.978723 (-8575 1850);
PAINT WHITE (-8575 1850);
DISPLAY INVISIBLE (-8575 1850);
FORCEPROP 1 LAST PART_NUMBER CS24702JB10
J 2
(-8575 1800);
DISPLAY 0.510638 (-8575 1800);
PAINT SKYBLUE (-8575 1800);
DISPLAY INVISIBLE (-8575 1800);
FORCEADD Q_RES..1
R 2
(-8625 1650);
FORCEPROP 1 LAST LOCATION R549
J 0
(-8350 1650);
DISPLAY 0.489362 (-8350 1650);
PAINT SKYBLUE (-8350 1650);
FORCEPROP 0 LAST $SEC 1
J 2
(-8475 1700);
DISPLAY 0.680851 (-8475 1700);
PAINT MONO (-8475 1700);
DISPLAY INVISIBLE (-8475 1700);
FORCEPROP 0 LAST CDS_SEC 1
J 2
(-8475 1700);
DISPLAY 1.021277 (-8475 1700);
DISPLAY INVISIBLE (-8475 1700);
FORCEPROP 1 LASTPIN (-8525 1650) $PN 1
J 2
(-8537 1662);
DISPLAY 0.489362 (-8537 1662);
PAINT MONO (-8537 1662);
FORCEPROP 1 LASTPIN (-8725 1650) $PN 2
J 2
(-8687 1662);
DISPLAY 0.489362 (-8687 1662);
PAINT MONO (-8687 1662);
FORCEPROP 1 LAST VALUE 4.7K
J 0
(-8875 1650);
DISPLAY 0.489362 (-8875 1650);
PAINT SKYBLUE (-8875 1650);
FORCEPROP 1 LAST MATERIAL EMPTY
J 2
(-8375 1650);
DISPLAY 0.489362 (-8375 1650);
PAINT RED (-8375 1650);
FORCEPROP 1 LAST PACK_TYPE 0402LF
J 2
(-8875 1500);
DISPLAY 0.510638 (-8875 1500);
PAINT SKYBLUE (-8875 1500);
DISPLAY INVISIBLE (-8875 1500);
FORCEPROP 1 LAST TOLERANCE 5%
J 2
(-8750 1650);
DISPLAY 0.510638 (-8750 1650);
PAINT SKYBLUE (-8750 1650);
DISPLAY INVISIBLE (-8750 1650);
FORCEPROP 1 LAST WATTAGE 1/16W
J 0
(-8600 1500);
DISPLAY 0.510638 (-8600 1500);
PAINT SKYBLUE (-8600 1500);
DISPLAY INVISIBLE (-8600 1500);
FORCEPROP 2 LAST CDS_LIB pure_quanta
J 2
(-8625 1650);
DISPLAY INVISIBLE (-8625 1650);
FORCEPROP 1 LAST PATH I353
J 2
(-8575 1800);
DISPLAY 0.978723 (-8575 1800);
PAINT WHITE (-8575 1800);
DISPLAY INVISIBLE (-8575 1800);
FORCEPROP 1 LAST PART_NUMBER CS24702JB10
J 2
(-8575 1750);
DISPLAY 0.510638 (-8575 1750);
PAINT SKYBLUE (-8575 1750);
DISPLAY INVISIBLE (-8575 1750);
FORCEADD Q_RES..1
(-8625 1850);
FORCEPROP 1 LAST LOCATION R562
J 0
(-8350 1850);
DISPLAY 0.489362 (-8350 1850);
PAINT SKYBLUE (-8350 1850);
FORCEPROP 0 LAST $SEC 1
J 0
(-8350 1875);
DISPLAY 0.680851 (-8350 1875);
PAINT MONO (-8350 1875);
DISPLAY INVISIBLE (-8350 1875);
FORCEPROP 0 LAST CDS_SEC 1
J 0
(-8350 1875);
DISPLAY 0.680851 (-8350 1875);
DISPLAY INVISIBLE (-8350 1875);
FORCEPROP 1 LASTPIN (-8725 1850) $PN 1
J 0
(-8713 1862);
DISPLAY 0.489362 (-8713 1862);
PAINT MONO (-8713 1862);
FORCEPROP 1 LASTPIN (-8525 1850) $PN 2
J 0
(-8563 1862);
DISPLAY 0.489362 (-8563 1862);
PAINT MONO (-8563 1862);
FORCEPROP 1 LAST VALUE 2.2K
J 0
(-8875 1850);
DISPLAY 0.489362 (-8875 1850);
PAINT SKYBLUE (-8875 1850);
FORCEPROP 2 LAST CDS_LIB pure_quanta
J 0
(-8625 1850);
DISPLAY INVISIBLE (-8625 1850);
FORCEPROP 1 LAST WATTAGE 1/16W
J 2
(-8650 1700);
DISPLAY 0.978723 (-8650 1700);
PAINT SKYBLUE (-8650 1700);
DISPLAY INVISIBLE (-8650 1700);
FORCEPROP 1 LAST MATERIAL CHIP
J 0
(-8625 1700);
DISPLAY 0.978723 (-8625 1700);
PAINT SKYBLUE (-8625 1700);
DISPLAY INVISIBLE (-8625 1700);
FORCEPROP 1 LAST TOLERANCE 5%
J 0
(-8625 1750);
DISPLAY 0.978723 (-8625 1750);
PAINT SKYBLUE (-8625 1750);
DISPLAY INVISIBLE (-8625 1750);
FORCEPROP 1 LAST PACK_TYPE 0402LF
J 0
(-8375 1700);
DISPLAY 0.978723 (-8375 1700);
PAINT SKYBLUE (-8375 1700);
DISPLAY INVISIBLE (-8375 1700);
FORCEPROP 1 LAST PATH I355
J 0
(-8675 2000);
DISPLAY 0.978723 (-8675 2000);
PAINT WHITE (-8675 2000);
DISPLAY INVISIBLE (-8675 2000);
FORCEPROP 1 LAST PART_NUMBER CS22202JB07
J 0
(-8675 1950);
DISPLAY 0.978723 (-8675 1950);
PAINT SKYBLUE (-8675 1950);
DISPLAY INVISIBLE (-8675 1950);
FORCEADD Q_RES..1
(-8625 1900);
FORCEPROP 1 LAST LOCATION R559
J 0
(-8350 1900);
DISPLAY 0.489362 (-8350 1900);
PAINT SKYBLUE (-8350 1900);
FORCEPROP 0 LAST $SEC 1
J 0
(-8350 1925);
DISPLAY 0.680851 (-8350 1925);
PAINT MONO (-8350 1925);
DISPLAY INVISIBLE (-8350 1925);
FORCEPROP 0 LAST CDS_SEC 1
J 0
(-8350 1925);
DISPLAY 0.680851 (-8350 1925);
DISPLAY INVISIBLE (-8350 1925);
FORCEPROP 1 LASTPIN (-8725 1900) $PN 1
J 0
(-8713 1912);
DISPLAY 0.489362 (-8713 1912);
PAINT MONO (-8713 1912);
FORCEPROP 1 LASTPIN (-8525 1900) $PN 2
J 0
(-8563 1912);
DISPLAY 0.489362 (-8563 1912);
PAINT MONO (-8563 1912);
FORCEPROP 1 LAST VALUE 2.2K
J 0
(-8875 1900);
DISPLAY 0.489362 (-8875 1900);
PAINT SKYBLUE (-8875 1900);
FORCEPROP 2 LAST CDS_LIB pure_quanta
J 0
(-8625 1900);
DISPLAY INVISIBLE (-8625 1900);
FORCEPROP 1 LAST WATTAGE 1/16W
J 2
(-8650 1750);
DISPLAY 0.978723 (-8650 1750);
PAINT SKYBLUE (-8650 1750);
DISPLAY INVISIBLE (-8650 1750);
FORCEPROP 1 LAST MATERIAL CHIP
J 0
(-8625 1750);
DISPLAY 0.978723 (-8625 1750);
PAINT SKYBLUE (-8625 1750);
DISPLAY INVISIBLE (-8625 1750);
FORCEPROP 1 LAST TOLERANCE 5%
J 0
(-8625 1800);
DISPLAY 0.978723 (-8625 1800);
PAINT SKYBLUE (-8625 1800);
DISPLAY INVISIBLE (-8625 1800);
FORCEPROP 1 LAST PACK_TYPE 0402LF
J 0
(-8375 1750);
DISPLAY 0.978723 (-8375 1750);
PAINT SKYBLUE (-8375 1750);
DISPLAY INVISIBLE (-8375 1750);
FORCEPROP 1 LAST PATH I356
J 0
(-8675 2050);
DISPLAY 0.978723 (-8675 2050);
PAINT WHITE (-8675 2050);
DISPLAY INVISIBLE (-8675 2050);
FORCEPROP 1 LAST PART_NUMBER CS22202JB07
J 0
(-8675 2000);
DISPLAY 0.978723 (-8675 2000);
PAINT SKYBLUE (-8675 2000);
DISPLAY INVISIBLE (-8675 2000);
FORCEADD Q_RES..1
(-8625 2000);
FORCEPROP 1 LAST LOCATION R556
J 0
(-8350 2000);
DISPLAY 0.489362 (-8350 2000);
PAINT SKYBLUE (-8350 2000);
FORCEPROP 0 LAST $SEC 1
J 0
(-8350 2025);
DISPLAY 0.680851 (-8350 2025);
PAINT MONO (-8350 2025);
DISPLAY INVISIBLE (-8350 2025);
FORCEPROP 0 LAST CDS_SEC 1
J 0
(-8350 2025);
DISPLAY 0.680851 (-8350 2025);
DISPLAY INVISIBLE (-8350 2025);
FORCEPROP 1 LASTPIN (-8725 2000) $PN 1
J 0
(-8713 2012);
DISPLAY 0.489362 (-8713 2012);
PAINT MONO (-8713 2012);
FORCEPROP 1 LASTPIN (-8525 2000) $PN 2
J 0
(-8563 2012);
DISPLAY 0.489362 (-8563 2012);
PAINT MONO (-8563 2012);
FORCEPROP 1 LAST MATERIAL EMPTY
J 0
(-8525 2000);
DISPLAY 0.510638 (-8525 2000);
PAINT RED (-8525 2000);
FORCEPROP 1 LAST VALUE 1K
J 0
(-8875 2000);
DISPLAY 0.489362 (-8875 2000);
PAINT SKYBLUE (-8875 2000);
FORCEPROP 1 LAST PACK_TYPE 0402LF
J 0
(-8375 1850);
DISPLAY 0.978723 (-8375 1850);
PAINT SKYBLUE (-8375 1850);
DISPLAY INVISIBLE (-8375 1850);
FORCEPROP 1 LAST WATTAGE 1/16W
J 2
(-8650 1850);
DISPLAY 0.978723 (-8650 1850);
PAINT SKYBLUE (-8650 1850);
DISPLAY INVISIBLE (-8650 1850);
FORCEPROP 2 LAST CDS_LIB pure_quanta
J 0
(-8625 2000);
DISPLAY INVISIBLE (-8625 2000);
FORCEPROP 1 LAST TOLERANCE 1%
J 0
(-8625 1900);
DISPLAY 0.978723 (-8625 1900);
PAINT SKYBLUE (-8625 1900);
DISPLAY INVISIBLE (-8625 1900);
FORCEPROP 1 LAST PATH I357
J 0
(-8675 2150);
DISPLAY 0.978723 (-8675 2150);
PAINT WHITE (-8675 2150);
DISPLAY INVISIBLE (-8675 2150);
FORCEPROP 1 LAST PART_NUMBER CS21002FB06
J 0
(-8675 2100);
DISPLAY 0.978723 (-8675 2100);
PAINT SKYBLUE (-8675 2100);
DISPLAY INVISIBLE (-8675 2100);
FORCEADD Q_RES..1
R 2
(-8625 2050);
FORCEPROP 1 LAST LOCATION R553
J 0
(-8350 2050);
DISPLAY 0.489362 (-8350 2050);
PAINT SKYBLUE (-8350 2050);
FORCEPROP 0 LAST $SEC 1
J 2
(-8475 2100);
DISPLAY 0.680851 (-8475 2100);
PAINT MONO (-8475 2100);
DISPLAY INVISIBLE (-8475 2100);
FORCEPROP 0 LAST CDS_SEC 1
J 2
(-8475 2100);
DISPLAY 1.021277 (-8475 2100);
DISPLAY INVISIBLE (-8475 2100);
FORCEPROP 1 LASTPIN (-8525 2050) $PN 1
J 2
(-8537 2062);
DISPLAY 0.489362 (-8537 2062);
PAINT MONO (-8537 2062);
FORCEPROP 1 LASTPIN (-8725 2050) $PN 2
J 2
(-8687 2062);
DISPLAY 0.489362 (-8687 2062);
PAINT MONO (-8687 2062);
FORCEPROP 1 LAST VALUE 4.7K
J 0
(-8875 2050);
DISPLAY 0.489362 (-8875 2050);
PAINT SKYBLUE (-8875 2050);
FORCEPROP 1 LAST PACK_TYPE 0402LF
J 2
(-8875 1900);
DISPLAY 0.510638 (-8875 1900);
PAINT SKYBLUE (-8875 1900);
DISPLAY INVISIBLE (-8875 1900);
FORCEPROP 1 LAST TOLERANCE 5%
J 2
(-8750 2050);
DISPLAY 0.510638 (-8750 2050);
PAINT SKYBLUE (-8750 2050);
DISPLAY INVISIBLE (-8750 2050);
FORCEPROP 1 LAST MATERIAL CHIP
J 2
(-8725 2025);
DISPLAY 0.489362 (-8725 2025);
PAINT SKYBLUE (-8725 2025);
DISPLAY INVISIBLE (-8725 2025);
FORCEPROP 1 LAST WATTAGE 1/16W
J 0
(-8600 1900);
DISPLAY 0.510638 (-8600 1900);
PAINT SKYBLUE (-8600 1900);
DISPLAY INVISIBLE (-8600 1900);
FORCEPROP 2 LAST CDS_LIB pure_quanta
J 2
(-8625 2050);
DISPLAY INVISIBLE (-8625 2050);
FORCEPROP 1 LAST PATH I359
J 2
(-8575 2200);
DISPLAY 0.978723 (-8575 2200);
PAINT WHITE (-8575 2200);
DISPLAY INVISIBLE (-8575 2200);
FORCEPROP 1 LAST PART_NUMBER CS24702JB10
J 2
(-8575 2150);
DISPLAY 0.404255 (-8575 2150);
PAINT SKYBLUE (-8575 2150);
DISPLAY INVISIBLE (-8575 2150);
FORCEADD Q_RES..1
R 2
(-8625 2100);
FORCEPROP 1 LAST LOCATION R551
J 0
(-8350 2100);
DISPLAY 0.489362 (-8350 2100);
PAINT SKYBLUE (-8350 2100);
FORCEPROP 0 LAST $SEC 1
J 2
(-8475 2150);
DISPLAY 0.680851 (-8475 2150);
PAINT MONO (-8475 2150);
DISPLAY INVISIBLE (-8475 2150);
FORCEPROP 0 LAST CDS_SEC 1
J 2
(-8475 2150);
DISPLAY 1.021277 (-8475 2150);
DISPLAY INVISIBLE (-8475 2150);
FORCEPROP 1 LASTPIN (-8525 2100) $PN 1
J 2
(-8537 2112);
DISPLAY 0.489362 (-8537 2112);
PAINT MONO (-8537 2112);
FORCEPROP 1 LASTPIN (-8725 2100) $PN 2
J 2
(-8687 2112);
DISPLAY 0.489362 (-8687 2112);
PAINT MONO (-8687 2112);
FORCEPROP 1 LAST VALUE 4.7K
J 0
(-8875 2100);
DISPLAY 0.489362 (-8875 2100);
PAINT SKYBLUE (-8875 2100);
FORCEPROP 1 LAST PACK_TYPE 0402LF
J 2
(-8875 1950);
DISPLAY 0.510638 (-8875 1950);
PAINT SKYBLUE (-8875 1950);
DISPLAY INVISIBLE (-8875 1950);
FORCEPROP 1 LAST TOLERANCE 5%
J 2
(-8750 2100);
DISPLAY 0.510638 (-8750 2100);
PAINT SKYBLUE (-8750 2100);
DISPLAY INVISIBLE (-8750 2100);
FORCEPROP 1 LAST MATERIAL CHIP
J 2
(-8725 2075);
DISPLAY 0.489362 (-8725 2075);
PAINT SKYBLUE (-8725 2075);
DISPLAY INVISIBLE (-8725 2075);
FORCEPROP 1 LAST WATTAGE 1/16W
J 0
(-8600 1950);
DISPLAY 0.510638 (-8600 1950);
PAINT SKYBLUE (-8600 1950);
DISPLAY INVISIBLE (-8600 1950);
FORCEPROP 2 LAST CDS_LIB pure_quanta
J 2
(-8625 2100);
DISPLAY INVISIBLE (-8625 2100);
FORCEPROP 1 LAST PATH I360
J 2
(-8575 2250);
DISPLAY 0.978723 (-8575 2250);
PAINT WHITE (-8575 2250);
DISPLAY INVISIBLE (-8575 2250);
FORCEPROP 1 LAST PART_NUMBER CS24702JB10
J 2
(-8575 2200);
DISPLAY 0.510638 (-8575 2200);
PAINT SKYBLUE (-8575 2200);
DISPLAY INVISIBLE (-8575 2200);
FORCEADD UNIVERSAL_POWER..1
R 2
(-8975 2500);
FORCEPROP 3 LASTPIN (-8975 2450) SIG_NAME PVDD18_S5_P1\g
J 0
(-8965 2460);
DISPLAY 0.659574 (-8965 2460);
PAINT MONO (-8965 2460);
DISPLAY INVISIBLE (-8965 2460);
FORCEPROP 1 LAST HDL_POWER PVDD18_S5_P1
J 1
(-8950 2550);
DISPLAY 0.489362 (-8950 2550);
PAINT GREEN (-8950 2550);
FORCEPROP 2 LAST CDS_LIB pure_quanta_power
J 2
(-8975 2500);
DISPLAY INVISIBLE (-8975 2500);
FORCEPROP 1 LAST PATH I361
J 2
(-9025 2525);
DISPLAY 0.872340 (-9025 2525);
PAINT AQUA (-9025 2525);
DISPLAY INVISIBLE (-9025 2525);
FORCEADD Q_RES..1
R 2
(-8625 2250);
FORCEPROP 1 LAST LOCATION R547
J 0
(-8350 2250);
DISPLAY 0.489362 (-8350 2250);
PAINT SKYBLUE (-8350 2250);
FORCEPROP 0 LAST $SEC 1
J 2
(-8475 2300);
DISPLAY 0.680851 (-8475 2300);
PAINT MONO (-8475 2300);
DISPLAY INVISIBLE (-8475 2300);
FORCEPROP 0 LAST CDS_SEC 1
J 2
(-8475 2300);
DISPLAY 1.021277 (-8475 2300);
DISPLAY INVISIBLE (-8475 2300);
FORCEPROP 1 LASTPIN (-8525 2250) $PN 1
J 2
(-8537 2262);
DISPLAY 0.489362 (-8537 2262);
PAINT MONO (-8537 2262);
FORCEPROP 1 LASTPIN (-8725 2250) $PN 2
J 2
(-8687 2262);
DISPLAY 0.489362 (-8687 2262);
PAINT MONO (-8687 2262);
FORCEPROP 1 LAST VALUE 4.7K
J 0
(-8875 2250);
DISPLAY 0.489362 (-8875 2250);
PAINT SKYBLUE (-8875 2250);
FORCEPROP 1 LAST PACK_TYPE 0402LF
J 2
(-8875 2100);
DISPLAY 0.510638 (-8875 2100);
PAINT SKYBLUE (-8875 2100);
DISPLAY INVISIBLE (-8875 2100);
FORCEPROP 1 LAST TOLERANCE 5%
J 2
(-8750 2250);
DISPLAY 0.510638 (-8750 2250);
PAINT SKYBLUE (-8750 2250);
DISPLAY INVISIBLE (-8750 2250);
FORCEPROP 1 LAST MATERIAL CHIP
J 2
(-8725 2225);
DISPLAY 0.489362 (-8725 2225);
PAINT SKYBLUE (-8725 2225);
DISPLAY INVISIBLE (-8725 2225);
FORCEPROP 1 LAST WATTAGE 1/16W
J 0
(-8600 2100);
DISPLAY 0.510638 (-8600 2100);
PAINT SKYBLUE (-8600 2100);
DISPLAY INVISIBLE (-8600 2100);
FORCEPROP 2 LAST CDS_LIB pure_quanta
J 2
(-8625 2250);
DISPLAY INVISIBLE (-8625 2250);
FORCEPROP 1 LAST PATH I362
J 2
(-8575 2400);
DISPLAY 0.978723 (-8575 2400);
PAINT WHITE (-8575 2400);
DISPLAY INVISIBLE (-8575 2400);
FORCEPROP 1 LAST PART_NUMBER CS24702JB10
J 2
(-8575 2350);
DISPLAY 0.510638 (-8575 2350);
PAINT SKYBLUE (-8575 2350);
DISPLAY INVISIBLE (-8575 2350);
FORCEADD Q_RES..1
R 2
(-8625 2150);
FORCEPROP 1 LAST LOCATION R550
J 0
(-8350 2150);
DISPLAY 0.489362 (-8350 2150);
PAINT SKYBLUE (-8350 2150);
FORCEPROP 0 LAST $SEC 1
J 2
(-8475 2200);
DISPLAY 0.680851 (-8475 2200);
PAINT MONO (-8475 2200);
DISPLAY INVISIBLE (-8475 2200);
FORCEPROP 0 LAST CDS_SEC 1
J 2
(-8475 2200);
DISPLAY 1.021277 (-8475 2200);
DISPLAY INVISIBLE (-8475 2200);
FORCEPROP 1 LASTPIN (-8525 2150) $PN 1
J 2
(-8537 2162);
DISPLAY 0.489362 (-8537 2162);
PAINT MONO (-8537 2162);
FORCEPROP 1 LASTPIN (-8725 2150) $PN 2
J 2
(-8687 2162);
DISPLAY 0.489362 (-8687 2162);
PAINT MONO (-8687 2162);
FORCEPROP 1 LAST VALUE 4.7K
J 0
(-8875 2150);
DISPLAY 0.489362 (-8875 2150);
PAINT SKYBLUE (-8875 2150);
FORCEPROP 1 LAST PACK_TYPE 0402LF
J 2
(-8875 2000);
DISPLAY 0.510638 (-8875 2000);
PAINT SKYBLUE (-8875 2000);
DISPLAY INVISIBLE (-8875 2000);
FORCEPROP 1 LAST TOLERANCE 5%
J 2
(-8750 2150);
DISPLAY 0.510638 (-8750 2150);
PAINT SKYBLUE (-8750 2150);
DISPLAY INVISIBLE (-8750 2150);
FORCEPROP 1 LAST MATERIAL CHIP
J 2
(-8725 2125);
DISPLAY 0.489362 (-8725 2125);
PAINT SKYBLUE (-8725 2125);
DISPLAY INVISIBLE (-8725 2125);
FORCEPROP 1 LAST WATTAGE 1/16W
J 0
(-8600 2000);
DISPLAY 0.510638 (-8600 2000);
PAINT SKYBLUE (-8600 2000);
DISPLAY INVISIBLE (-8600 2000);
FORCEPROP 2 LAST CDS_LIB pure_quanta
J 2
(-8625 2150);
DISPLAY INVISIBLE (-8625 2150);
FORCEPROP 1 LAST PATH I363
J 2
(-8575 2300);
DISPLAY 0.978723 (-8575 2300);
PAINT WHITE (-8575 2300);
DISPLAY INVISIBLE (-8575 2300);
FORCEPROP 1 LAST PART_NUMBER CS24702JB10
J 2
(-8575 2250);
DISPLAY 0.510638 (-8575 2250);
PAINT SKYBLUE (-8575 2250);
DISPLAY INVISIBLE (-8575 2250);
FORCEADD Q_RES..1
(-8625 2200);
FORCEPROP 1 LAST LOCATION R557
J 0
(-8350 2200);
DISPLAY 0.489362 (-8350 2200);
PAINT SKYBLUE (-8350 2200);
FORCEPROP 0 LAST $SEC 1
J 0
(-8350 2225);
DISPLAY 0.680851 (-8350 2225);
PAINT MONO (-8350 2225);
DISPLAY INVISIBLE (-8350 2225);
FORCEPROP 0 LAST CDS_SEC 1
J 0
(-8350 2225);
DISPLAY 0.680851 (-8350 2225);
DISPLAY INVISIBLE (-8350 2225);
FORCEPROP 1 LASTPIN (-8725 2200) $PN 1
J 0
(-8713 2212);
DISPLAY 0.489362 (-8713 2212);
PAINT MONO (-8713 2212);
FORCEPROP 1 LASTPIN (-8525 2200) $PN 2
J 0
(-8563 2212);
DISPLAY 0.489362 (-8563 2212);
PAINT MONO (-8563 2212);
FORCEPROP 1 LAST VALUE 1K
J 0
(-8875 2200);
DISPLAY 0.489362 (-8875 2200);
PAINT SKYBLUE (-8875 2200);
FORCEPROP 1 LAST MATERIAL EMPTY
J 0
(-8525 2200);
DISPLAY 0.510638 (-8525 2200);
PAINT RED (-8525 2200);
FORCEPROP 2 LAST CDS_LIB pure_quanta
J 0
(-8625 2200);
DISPLAY INVISIBLE (-8625 2200);
FORCEPROP 1 LAST WATTAGE 1/16W
J 2
(-8650 2050);
DISPLAY 0.978723 (-8650 2050);
PAINT SKYBLUE (-8650 2050);
DISPLAY INVISIBLE (-8650 2050);
FORCEPROP 1 LAST PACK_TYPE 0402LF
J 0
(-8375 2050);
DISPLAY 0.978723 (-8375 2050);
PAINT SKYBLUE (-8375 2050);
DISPLAY INVISIBLE (-8375 2050);
FORCEPROP 1 LAST TOLERANCE 1%
J 0
(-8625 2100);
DISPLAY 0.978723 (-8625 2100);
PAINT SKYBLUE (-8625 2100);
DISPLAY INVISIBLE (-8625 2100);
FORCEPROP 1 LAST PATH I364
J 0
(-8675 2350);
DISPLAY 0.978723 (-8675 2350);
PAINT WHITE (-8675 2350);
DISPLAY INVISIBLE (-8675 2350);
FORCEPROP 1 LAST PART_NUMBER CS21002FB06
J 0
(-8675 2300);
DISPLAY 0.978723 (-8675 2300);
PAINT SKYBLUE (-8675 2300);
DISPLAY INVISIBLE (-8675 2300);
FORCEADD Q_RES..2
(-9050 3000);
FORCEPROP 1 LAST LOCATION R541
J 0
(-9000 3075);
DISPLAY 0.489362 (-9000 3075);
PAINT SKYBLUE (-9000 3075);
FORCEPROP 0 LAST $SEC 1
J 2
(-9000 3125);
DISPLAY 0.680851 (-9000 3125);
PAINT MONO (-9000 3125);
DISPLAY INVISIBLE (-9000 3125);
FORCEPROP 0 LAST CDS_SEC 1
J 2
(-9000 3125);
DISPLAY 1.021277 (-9000 3125);
DISPLAY INVISIBLE (-9000 3125);
FORCEPROP 1 LASTPIN (-9050 3100) $PN 1
J 0
(-9045 3062);
DISPLAY 0.489362 (-9045 3062);
PAINT MONO (-9045 3062);
FORCEPROP 1 LASTPIN (-9050 2900) $PN 2
J 0
(-9045 2910);
DISPLAY 0.489362 (-9045 2910);
PAINT MONO (-9045 2910);
FORCEPROP 1 LAST VALUE 1K
J 0
(-9000 3050);
DISPLAY 0.489362 (-9000 3050);
PAINT SKYBLUE (-9000 3050);
FORCEPROP 1 LAST MATERIAL EMPTY
J 0
(-9000 2975);
DISPLAY 0.489362 (-9000 2975);
PAINT RED (-9000 2975);
FORCEPROP 1 LAST TOLERANCE 1%
J 0
(-9000 3025);
DISPLAY 0.489362 (-9000 3025);
PAINT SKYBLUE (-9000 3025);
FORCEPROP 1 LAST PACK_TYPE 0402LF
J 0
(-9000 2950);
DISPLAY 0.489362 (-9000 2950);
PAINT SKYBLUE (-9000 2950);
DISPLAY INVISIBLE (-9000 2950);
FORCEPROP 1 LAST WATTAGE 1/16W
J 0
(-9000 3000);
DISPLAY 0.489362 (-9000 3000);
PAINT SKYBLUE (-9000 3000);
DISPLAY INVISIBLE (-9000 3000);
FORCEPROP 2 LAST CDS_LIB pure_quanta
J 2
(-9050 3000);
DISPLAY INVISIBLE (-9050 3000);
FORCEPROP 1 LAST PATH I365
J 0
(-9000 3175);
DISPLAY 0.978723 (-9000 3175);
PAINT WHITE (-9000 3175);
DISPLAY INVISIBLE (-9000 3175);
FORCEPROP 1 LAST PART_NUMBER CS21002FB06
J 0
(-9000 2925);
DISPLAY 0.489362 (-9000 2925);
PAINT SKYBLUE (-9000 2925);
DISPLAY INVISIBLE (-9000 2925);
FORCEADD Q_RES..2
(-8875 3000);
FORCEPROP 1 LAST LOCATION R542
J 0
(-8825 3075);
DISPLAY 0.489362 (-8825 3075);
PAINT SKYBLUE (-8825 3075);
FORCEPROP 0 LAST $SEC 1
J 2
(-8825 3125);
DISPLAY 0.680851 (-8825 3125);
PAINT MONO (-8825 3125);
DISPLAY INVISIBLE (-8825 3125);
FORCEPROP 0 LAST CDS_SEC 1
J 2
(-8825 3125);
DISPLAY 1.021277 (-8825 3125);
DISPLAY INVISIBLE (-8825 3125);
FORCEPROP 1 LASTPIN (-8875 3100) $PN 1
J 0
(-8870 3062);
DISPLAY 0.489362 (-8870 3062);
PAINT MONO (-8870 3062);
FORCEPROP 1 LASTPIN (-8875 2900) $PN 2
J 0
(-8870 2910);
DISPLAY 0.489362 (-8870 2910);
PAINT MONO (-8870 2910);
FORCEPROP 1 LAST MATERIAL EMPTY
J 0
(-8825 2975);
DISPLAY 0.489362 (-8825 2975);
PAINT RED (-8825 2975);
FORCEPROP 1 LAST VALUE 1K
J 0
(-8825 3050);
DISPLAY 0.489362 (-8825 3050);
PAINT SKYBLUE (-8825 3050);
FORCEPROP 1 LAST TOLERANCE 1%
J 0
(-8825 3025);
DISPLAY 0.489362 (-8825 3025);
PAINT SKYBLUE (-8825 3025);
FORCEPROP 1 LAST PACK_TYPE 0402LF
J 0
(-8825 2950);
DISPLAY 0.489362 (-8825 2950);
PAINT SKYBLUE (-8825 2950);
DISPLAY INVISIBLE (-8825 2950);
FORCEPROP 1 LAST WATTAGE 1/16W
J 0
(-8825 3000);
DISPLAY 0.489362 (-8825 3000);
PAINT SKYBLUE (-8825 3000);
DISPLAY INVISIBLE (-8825 3000);
FORCEPROP 2 LAST CDS_LIB pure_quanta
J 2
(-8875 3000);
DISPLAY INVISIBLE (-8875 3000);
FORCEPROP 1 LAST PATH I366
J 0
(-8825 3175);
DISPLAY 0.978723 (-8825 3175);
PAINT WHITE (-8825 3175);
DISPLAY INVISIBLE (-8825 3175);
FORCEPROP 1 LAST PART_NUMBER CS21002FB06
J 0
(-8825 2925);
DISPLAY 0.489362 (-8825 2925);
PAINT SKYBLUE (-8825 2925);
DISPLAY INVISIBLE (-8825 2925);
FORCEADD Q_RES..2
(-8700 3000);
FORCEPROP 1 LAST LOCATION R543
J 0
(-8655 3075);
DISPLAY 0.489362 (-8655 3075);
PAINT SKYBLUE (-8655 3075);
FORCEPROP 0 LAST $SEC 1
J 0
(-8650 3150);
DISPLAY 0.680851 (-8650 3150);
PAINT MONO (-8650 3150);
DISPLAY INVISIBLE (-8650 3150);
FORCEPROP 0 LAST CDS_SEC 1
J 0
(-8650 3150);
DISPLAY 1.021277 (-8650 3150);
DISPLAY INVISIBLE (-8650 3150);
FORCEPROP 1 LASTPIN (-8700 3100) $PN 1
J 0
(-8695 3062);
DISPLAY 0.489362 (-8695 3062);
PAINT MONO (-8695 3062);
FORCEPROP 1 LASTPIN (-8700 2900) $PN 2
J 0
(-8695 2910);
DISPLAY 0.489362 (-8695 2910);
PAINT MONO (-8695 2910);
FORCEPROP 1 LAST VALUE 1K
J 0
(-8650 3050);
DISPLAY 0.489362 (-8650 3050);
PAINT SKYBLUE (-8650 3050);
FORCEPROP 1 LAST MATERIAL EMPTY
J 0
(-8650 2975);
DISPLAY 0.489362 (-8650 2975);
PAINT RED (-8650 2975);
FORCEPROP 1 LAST TOLERANCE 1%
J 0
(-8650 3025);
DISPLAY 0.489362 (-8650 3025);
PAINT SKYBLUE (-8650 3025);
FORCEPROP 1 LAST PACK_TYPE 0402LF
J 0
(-8650 2950);
DISPLAY 0.489362 (-8650 2950);
PAINT SKYBLUE (-8650 2950);
DISPLAY INVISIBLE (-8650 2950);
FORCEPROP 1 LAST WATTAGE 1/16W
J 0
(-8650 3000);
DISPLAY 0.489362 (-8650 3000);
PAINT SKYBLUE (-8650 3000);
DISPLAY INVISIBLE (-8650 3000);
FORCEPROP 2 LAST CDS_LIB pure_quanta
J 0
(-8700 3000);
DISPLAY INVISIBLE (-8700 3000);
FORCEPROP 1 LAST PATH I367
J 0
(-8650 3175);
DISPLAY 0.978723 (-8650 3175);
PAINT WHITE (-8650 3175);
DISPLAY INVISIBLE (-8650 3175);
FORCEPROP 1 LAST PART_NUMBER CS21002FB06
J 0
(-8650 2925);
DISPLAY 0.489362 (-8650 2925);
PAINT SKYBLUE (-8650 2925);
DISPLAY INVISIBLE (-8650 2925);
FORCEADD Q_RES..2
(-8525 3000);
FORCEPROP 1 LAST LOCATION R563
J 0
(-8480 3075);
DISPLAY 0.489362 (-8480 3075);
PAINT SKYBLUE (-8480 3075);
FORCEPROP 0 LAST $SEC 1
J 0
(-8475 3150);
DISPLAY 0.680851 (-8475 3150);
PAINT MONO (-8475 3150);
DISPLAY INVISIBLE (-8475 3150);
FORCEPROP 0 LAST CDS_SEC 1
J 0
(-8475 3150);
DISPLAY 1.021277 (-8475 3150);
DISPLAY INVISIBLE (-8475 3150);
FORCEPROP 1 LASTPIN (-8525 3100) $PN 1
J 0
(-8520 3062);
DISPLAY 0.489362 (-8520 3062);
PAINT MONO (-8520 3062);
FORCEPROP 1 LASTPIN (-8525 2900) $PN 2
J 0
(-8520 2910);
DISPLAY 0.489362 (-8520 2910);
PAINT MONO (-8520 2910);
FORCEPROP 1 LAST MATERIAL EMPTY
J 0
(-8475 2975);
DISPLAY 0.489362 (-8475 2975);
PAINT RED (-8475 2975);
FORCEPROP 1 LAST VALUE 1K
J 0
(-8475 3050);
DISPLAY 0.489362 (-8475 3050);
PAINT SKYBLUE (-8475 3050);
FORCEPROP 1 LAST TOLERANCE 1%
J 0
(-8475 3025);
DISPLAY 0.489362 (-8475 3025);
PAINT SKYBLUE (-8475 3025);
FORCEPROP 2 LAST CDS_LIB pure_quanta
J 0
(-8525 3000);
DISPLAY INVISIBLE (-8525 3000);
FORCEPROP 1 LAST WATTAGE 1/16W
J 0
(-8475 3000);
DISPLAY 0.489362 (-8475 3000);
PAINT SKYBLUE (-8475 3000);
DISPLAY INVISIBLE (-8475 3000);
FORCEPROP 1 LAST PACK_TYPE 0402LF
J 0
(-8475 2950);
DISPLAY 0.489362 (-8475 2950);
PAINT SKYBLUE (-8475 2950);
DISPLAY INVISIBLE (-8475 2950);
FORCEPROP 1 LAST PATH I368
J 0
(-8475 3175);
DISPLAY 0.978723 (-8475 3175);
PAINT WHITE (-8475 3175);
DISPLAY INVISIBLE (-8475 3175);
FORCEPROP 1 LAST PART_NUMBER CS21002FB06
J 0
(-8475 2925);
DISPLAY 0.489362 (-8475 2925);
PAINT SKYBLUE (-8475 2925);
DISPLAY INVISIBLE (-8475 2925);
FORCEADD VCC_CORE..1
(-8525 3300);
FORCEPROP 3 LASTPIN (-8525 3250) SIG_NAME PVDD11_S3_P1\g
J 0
(-8515 3260);
DISPLAY 0.659574 (-8515 3260);
PAINT MONO (-8515 3260);
DISPLAY INVISIBLE (-8515 3260);
FORCEPROP 1 LAST HDL_POWER PVDD11_S3_P1
J 1
(-8525 3350);
DISPLAY 0.489362 (-8525 3350);
PAINT GREEN (-8525 3350);
FORCEPROP 2 LAST CDS_LIB pure_quanta_power
J 0
(-8525 3300);
DISPLAY INVISIBLE (-8525 3300);
FORCEPROP 1 LAST PATH I369
J 0
(-8475 3325);
DISPLAY 0.872340 (-8475 3325);
PAINT AQUA (-8475 3325);
DISPLAY INVISIBLE (-8475 3325);
FORCEADD OFFPAGE..2
(-7625 1650);
FORCEPROP 2 LAST $XR0 55 
J 0
(-7436 1650);
DISPLAY 0.638298 (-7436 1650);
PAINT MONO (-7436 1650);
FORCEPROP 2 LAST CDS_LIB standard
J 2
(-7625 1650);
DISPLAY INVISIBLE (-7625 1650);
FORCEPROP 1 LAST OFFPAGE TRUE
J 0
(-7300 1525);
DISPLAY 0.872340 (-7300 1525);
PAINT GREEN (-7300 1525);
DISPLAY INVISIBLE (-7300 1525);
FORCEPROP 1 LAST COMMENT_BODY TRUE
J 0
(-7670 1555);
DISPLAY 0.872340 (-7670 1555);
PAINT GREEN (-7670 1555);
DISPLAY INVISIBLE (-7670 1555);
FORCEPROP 2 LAST PATH I370
J 0
(-7425 1700);
DISPLAY 0.680851 (-7425 1700);
DISPLAY INVISIBLE (-7425 1700);
FORCEADD OFFPAGE..2
(-7625 1700);
FORCEPROP 2 LAST $XR0 55 
J 0
(-7436 1700);
DISPLAY 0.638298 (-7436 1700);
PAINT MONO (-7436 1700);
FORCEPROP 2 LAST CDS_LIB standard
J 2
(-7625 1700);
DISPLAY INVISIBLE (-7625 1700);
FORCEPROP 1 LAST OFFPAGE TRUE
J 0
(-7300 1575);
DISPLAY 0.872340 (-7300 1575);
PAINT GREEN (-7300 1575);
DISPLAY INVISIBLE (-7300 1575);
FORCEPROP 1 LAST COMMENT_BODY TRUE
J 0
(-7670 1605);
DISPLAY 0.872340 (-7670 1605);
PAINT GREEN (-7670 1605);
DISPLAY INVISIBLE (-7670 1605);
FORCEPROP 2 LAST PATH I371
J 0
(-7425 1750);
DISPLAY 0.680851 (-7425 1750);
DISPLAY INVISIBLE (-7425 1750);
FORCEADD OFFPAGE..2
(-7625 1850);
FORCEPROP 2 LAST $XR1 55 
J 0
(-7346 1850);
DISPLAY 0.638298 (-7346 1850);
PAINT MONO (-7346 1850);
FORCEPROP 2 LAST $XR0 81 
J 0
(-7436 1850);
DISPLAY 0.638298 (-7436 1850);
PAINT MONO (-7436 1850);
FORCEPROP 2 LAST CDS_LIB standard
J 0
(-7625 1850);
DISPLAY INVISIBLE (-7625 1850);
FORCEPROP 1 LAST OFFPAGE TRUE
J 0
(-7300 1725);
DISPLAY 0.872340 (-7300 1725);
PAINT GREEN (-7300 1725);
DISPLAY INVISIBLE (-7300 1725);
FORCEPROP 1 LAST COMMENT_BODY TRUE
J 0
(-7670 1755);
DISPLAY 0.872340 (-7670 1755);
PAINT GREEN (-7670 1755);
DISPLAY INVISIBLE (-7670 1755);
FORCEPROP 2 LAST PATH I373
J 0
(-7325 1900);
DISPLAY 0.680851 (-7325 1900);
DISPLAY INVISIBLE (-7325 1900);
FORCEADD OFFPAGE..2
(-7625 1900);
FORCEPROP 2 LAST $XR1 55 
J 0
(-7346 1900);
DISPLAY 0.638298 (-7346 1900);
PAINT MONO (-7346 1900);
FORCEPROP 2 LAST $XR0 81 
J 0
(-7436 1900);
DISPLAY 0.638298 (-7436 1900);
PAINT MONO (-7436 1900);
FORCEPROP 2 LAST CDS_LIB standard
J 0
(-7625 1900);
DISPLAY INVISIBLE (-7625 1900);
FORCEPROP 1 LAST OFFPAGE TRUE
J 0
(-7300 1775);
DISPLAY 0.872340 (-7300 1775);
PAINT GREEN (-7300 1775);
DISPLAY INVISIBLE (-7300 1775);
FORCEPROP 1 LAST COMMENT_BODY TRUE
J 0
(-7670 1805);
DISPLAY 0.872340 (-7670 1805);
PAINT GREEN (-7670 1805);
DISPLAY INVISIBLE (-7670 1805);
FORCEPROP 2 LAST PATH I374
J 0
(-7325 1950);
DISPLAY 0.680851 (-7325 1950);
DISPLAY INVISIBLE (-7325 1950);
FORCEADD OFFPAGE..2
(-7625 1950);
FORCEPROP 2 LAST $XR1 81 
J 0
(-7346 1950);
DISPLAY 0.638298 (-7346 1950);
PAINT MONO (-7346 1950);
FORCEPROP 2 LAST $XR0 55 
J 0
(-7436 1950);
DISPLAY 0.638298 (-7436 1950);
PAINT MONO (-7436 1950);
FORCEPROP 2 LAST CDS_LIB standard
J 0
(-7625 1950);
DISPLAY INVISIBLE (-7625 1950);
FORCEPROP 1 LAST OFFPAGE TRUE
J 0
(-7300 1825);
DISPLAY 0.872340 (-7300 1825);
PAINT GREEN (-7300 1825);
DISPLAY INVISIBLE (-7300 1825);
FORCEPROP 1 LAST COMMENT_BODY TRUE
J 0
(-7670 1855);
DISPLAY 0.872340 (-7670 1855);
PAINT GREEN (-7670 1855);
DISPLAY INVISIBLE (-7670 1855);
FORCEPROP 2 LAST PATH I375
J 0
(-7325 2000);
DISPLAY 0.680851 (-7325 2000);
DISPLAY INVISIBLE (-7325 2000);
FORCEADD OFFPAGE..2
(-7625 2100);
FORCEPROP 2 LAST $XR1 81 
J 0
(-7346 2100);
DISPLAY 0.638298 (-7346 2100);
PAINT MONO (-7346 2100);
FORCEPROP 2 LAST $XR0 55 
J 0
(-7436 2100);
DISPLAY 0.638298 (-7436 2100);
PAINT MONO (-7436 2100);
FORCEPROP 2 LAST CDS_LIB standard
J 2
(-7625 2100);
DISPLAY INVISIBLE (-7625 2100);
FORCEPROP 1 LAST OFFPAGE TRUE
J 0
(-7300 1975);
DISPLAY 0.872340 (-7300 1975);
PAINT GREEN (-7300 1975);
DISPLAY INVISIBLE (-7300 1975);
FORCEPROP 1 LAST COMMENT_BODY TRUE
J 0
(-7670 2005);
DISPLAY 0.872340 (-7670 2005);
PAINT GREEN (-7670 2005);
DISPLAY INVISIBLE (-7670 2005);
FORCEPROP 2 LAST PATH I376
J 0
(-7325 2150);
DISPLAY 0.680851 (-7325 2150);
DISPLAY INVISIBLE (-7325 2150);
FORCEADD OFFPAGE..2
(-7625 2150);
FORCEPROP 2 LAST $XR1 81 
J 0
(-7346 2150);
DISPLAY 0.638298 (-7346 2150);
PAINT MONO (-7346 2150);
FORCEPROP 2 LAST $XR0 55 
J 0
(-7436 2150);
DISPLAY 0.638298 (-7436 2150);
PAINT MONO (-7436 2150);
FORCEPROP 2 LAST CDS_LIB standard
J 2
(-7625 2150);
DISPLAY INVISIBLE (-7625 2150);
FORCEPROP 1 LAST OFFPAGE TRUE
J 0
(-7300 2025);
DISPLAY 0.872340 (-7300 2025);
PAINT GREEN (-7300 2025);
DISPLAY INVISIBLE (-7300 2025);
FORCEPROP 1 LAST COMMENT_BODY TRUE
J 0
(-7670 2055);
DISPLAY 0.872340 (-7670 2055);
PAINT GREEN (-7670 2055);
DISPLAY INVISIBLE (-7670 2055);
FORCEPROP 2 LAST PATH I377
J 0
(-7325 2200);
DISPLAY 0.680851 (-7325 2200);
DISPLAY INVISIBLE (-7325 2200);
FORCEADD OFFPAGE..2
(-7625 2200);
FORCEPROP 2 LAST $XR3 78 
J 0
(-7166 2200);
DISPLAY 0.638298 (-7166 2200);
PAINT MONO (-7166 2200);
FORCEPROP 2 LAST $XR2 85 
J 0
(-7256 2200);
DISPLAY 0.638298 (-7256 2200);
PAINT MONO (-7256 2200);
FORCEPROP 2 LAST $XR1 81 
J 0
(-7346 2200);
DISPLAY 0.638298 (-7346 2200);
PAINT MONO (-7346 2200);
FORCEPROP 2 LAST $XR0 55 
J 0
(-7436 2200);
DISPLAY 0.638298 (-7436 2200);
PAINT MONO (-7436 2200);
FORCEPROP 2 LAST CDS_LIB standard
J 0
(-7625 2200);
DISPLAY INVISIBLE (-7625 2200);
FORCEPROP 1 LAST OFFPAGE TRUE
J 0
(-7300 2075);
DISPLAY 0.872340 (-7300 2075);
PAINT GREEN (-7300 2075);
DISPLAY INVISIBLE (-7300 2075);
FORCEPROP 1 LAST COMMENT_BODY TRUE
J 0
(-7670 2105);
DISPLAY 0.872340 (-7670 2105);
PAINT GREEN (-7670 2105);
DISPLAY INVISIBLE (-7670 2105);
FORCEPROP 2 LAST PATH I378
J 0
(-7150 2250);
DISPLAY 0.680851 (-7150 2250);
DISPLAY INVISIBLE (-7150 2250);
FORCEADD OFFPAGE..2
(-7625 2250);
FORCEPROP 2 LAST $XR1 82 
J 0
(-7346 2250);
DISPLAY 0.638298 (-7346 2250);
PAINT MONO (-7346 2250);
FORCEPROP 2 LAST $XR0 55 
J 0
(-7436 2250);
DISPLAY 0.638298 (-7436 2250);
PAINT MONO (-7436 2250);
FORCEPROP 2 LAST CDS_LIB standard
J 2
(-7625 2250);
DISPLAY INVISIBLE (-7625 2250);
FORCEPROP 1 LAST OFFPAGE TRUE
J 0
(-7300 2125);
DISPLAY 0.872340 (-7300 2125);
PAINT GREEN (-7300 2125);
DISPLAY INVISIBLE (-7300 2125);
FORCEPROP 1 LAST COMMENT_BODY TRUE
J 0
(-7670 2155);
DISPLAY 0.872340 (-7670 2155);
PAINT GREEN (-7670 2155);
DISPLAY INVISIBLE (-7670 2155);
FORCEPROP 2 LAST PATH I379
J 0
(-7325 2300);
DISPLAY 0.680851 (-7325 2300);
DISPLAY INVISIBLE (-7325 2300);
FORCEADD OFFPAGE..2
(-7625 2675);
FORCEPROP 2 LAST $XR1 159 
J 0
(-7346 2675);
DISPLAY 0.638298 (-7346 2675);
PAINT MONO (-7346 2675);
FORCEPROP 2 LAST $XR0 55 
J 0
(-7436 2675);
DISPLAY 0.638298 (-7436 2675);
PAINT MONO (-7436 2675);
FORCEPROP 2 LAST CDS_LIB standard
J 0
(-7625 2675);
DISPLAY INVISIBLE (-7625 2675);
FORCEPROP 1 LAST OFFPAGE TRUE
J 0
(-7300 2550);
DISPLAY 0.872340 (-7300 2550);
PAINT GREEN (-7300 2550);
DISPLAY INVISIBLE (-7300 2550);
FORCEPROP 1 LAST COMMENT_BODY TRUE
J 0
(-7670 2580);
DISPLAY 0.872340 (-7670 2580);
PAINT PEACH (-7670 2580);
DISPLAY INVISIBLE (-7670 2580);
FORCEPROP 2 LAST PATH I380
J 0
(-7325 2725);
DISPLAY 0.680851 (-7325 2725);
DISPLAY INVISIBLE (-7325 2725);
FORCEADD OFFPAGE..2
(-7625 2725);
FORCEPROP 2 LAST $XR1 159 
J 0
(-7346 2725);
DISPLAY 0.638298 (-7346 2725);
PAINT MONO (-7346 2725);
FORCEPROP 2 LAST $XR0 55 
J 0
(-7436 2725);
DISPLAY 0.638298 (-7436 2725);
PAINT MONO (-7436 2725);
FORCEPROP 2 LAST CDS_LIB standard
J 0
(-7625 2725);
DISPLAY INVISIBLE (-7625 2725);
FORCEPROP 1 LAST OFFPAGE TRUE
J 0
(-7300 2600);
DISPLAY 0.872340 (-7300 2600);
PAINT GREEN (-7300 2600);
DISPLAY INVISIBLE (-7300 2600);
FORCEPROP 1 LAST COMMENT_BODY TRUE
J 0
(-7670 2630);
DISPLAY 0.872340 (-7670 2630);
PAINT PEACH (-7670 2630);
DISPLAY INVISIBLE (-7670 2630);
FORCEPROP 2 LAST PATH I381
J 0
(-7325 2775);
DISPLAY 0.680851 (-7325 2775);
DISPLAY INVISIBLE (-7325 2775);
FORCEADD OFFPAGE..2
(-7625 2775);
FORCEPROP 2 LAST $XR1 159 
J 0
(-7346 2775);
DISPLAY 0.638298 (-7346 2775);
PAINT MONO (-7346 2775);
FORCEPROP 2 LAST $XR0 55 
J 0
(-7436 2775);
DISPLAY 0.638298 (-7436 2775);
PAINT MONO (-7436 2775);
FORCEPROP 2 LAST CDS_LIB standard
J 0
(-7625 2775);
DISPLAY INVISIBLE (-7625 2775);
FORCEPROP 1 LAST OFFPAGE TRUE
J 0
(-7300 2650);
DISPLAY 0.872340 (-7300 2650);
PAINT GREEN (-7300 2650);
DISPLAY INVISIBLE (-7300 2650);
FORCEPROP 1 LAST COMMENT_BODY TRUE
J 0
(-7670 2680);
DISPLAY 0.872340 (-7670 2680);
PAINT PEACH (-7670 2680);
DISPLAY INVISIBLE (-7670 2680);
FORCEPROP 2 LAST PATH I382
J 0
(-7325 2825);
DISPLAY 0.680851 (-7325 2825);
DISPLAY INVISIBLE (-7325 2825);
FORCEADD OFFPAGE..2
(-7625 2825);
FORCEPROP 2 LAST $XR1 159 
J 0
(-7346 2825);
DISPLAY 0.638298 (-7346 2825);
PAINT MONO (-7346 2825);
FORCEPROP 2 LAST $XR0 55 
J 0
(-7436 2825);
DISPLAY 0.638298 (-7436 2825);
PAINT MONO (-7436 2825);
FORCEPROP 2 LAST CDS_LIB standard
J 0
(-7625 2825);
DISPLAY INVISIBLE (-7625 2825);
FORCEPROP 1 LAST OFFPAGE TRUE
J 0
(-7300 2700);
DISPLAY 0.872340 (-7300 2700);
PAINT GREEN (-7300 2700);
DISPLAY INVISIBLE (-7300 2700);
FORCEPROP 1 LAST COMMENT_BODY TRUE
J 0
(-7670 2730);
DISPLAY 0.872340 (-7670 2730);
PAINT PEACH (-7670 2730);
DISPLAY INVISIBLE (-7670 2730);
FORCEPROP 2 LAST PATH I383
J 0
(-7325 2875);
DISPLAY 0.680851 (-7325 2875);
DISPLAY INVISIBLE (-7325 2875);
FORCEADD OFFPAGE..2
(-7625 2000);
FORCEPROP 2 LAST $XR2 85 
J 0
(-7256 2000);
DISPLAY 0.638298 (-7256 2000);
PAINT MONO (-7256 2000);
FORCEPROP 2 LAST $XR1 81 
J 0
(-7346 2000);
DISPLAY 0.638298 (-7346 2000);
PAINT MONO (-7346 2000);
FORCEPROP 2 LAST $XR0 55 
J 0
(-7436 2000);
DISPLAY 0.638298 (-7436 2000);
PAINT MONO (-7436 2000);
FORCEPROP 2 LAST CDS_LIB standard
J 0
(-7625 2000);
DISPLAY INVISIBLE (-7625 2000);
FORCEPROP 1 LAST OFFPAGE TRUE
J 0
(-7300 1875);
DISPLAY 0.872340 (-7300 1875);
PAINT GREEN (-7300 1875);
DISPLAY INVISIBLE (-7300 1875);
FORCEPROP 1 LAST COMMENT_BODY TRUE
J 0
(-7670 1905);
DISPLAY 0.872340 (-7670 1905);
PAINT GREEN (-7670 1905);
DISPLAY INVISIBLE (-7670 1905);
FORCEPROP 2 LAST PATH I384
J 0
(-7250 2050);
DISPLAY 0.680851 (-7250 2050);
DISPLAY INVISIBLE (-7250 2050);
FORCEADD OFFPAGE..2
(-7625 2050);
FORCEPROP 2 LAST $XR1 81 
J 0
(-7346 2050);
DISPLAY 0.638298 (-7346 2050);
PAINT MONO (-7346 2050);
FORCEPROP 2 LAST $XR0 55 
J 0
(-7436 2050);
DISPLAY 0.638298 (-7436 2050);
PAINT MONO (-7436 2050);
FORCEPROP 2 LAST CDS_LIB standard
J 0
(-7625 2050);
DISPLAY INVISIBLE (-7625 2050);
FORCEPROP 1 LAST OFFPAGE TRUE
J 0
(-7300 1925);
DISPLAY 0.872340 (-7300 1925);
PAINT GREEN (-7300 1925);
DISPLAY INVISIBLE (-7300 1925);
FORCEPROP 1 LAST COMMENT_BODY TRUE
J 0
(-7670 1955);
DISPLAY 0.872340 (-7670 1955);
PAINT GREEN (-7670 1955);
DISPLAY INVISIBLE (-7670 1955);
FORCEPROP 2 LAST PATH I385
J 0
(-7325 2100);
DISPLAY 0.680851 (-7325 2100);
DISPLAY INVISIBLE (-7325 2100);
FORCEADD Q_RES..2
R 2
(-4900 1900);
FORCEPROP 1 LAST LOCATION R5103
J 2
(-4725 1950);
DISPLAY 0.638298 (-4725 1950);
FORCEPROP 0 LAST $SEC 1
J 0
(-4725 2000);
DISPLAY 0.680851 (-4725 2000);
PAINT MONO (-4725 2000);
DISPLAY INVISIBLE (-4725 2000);
FORCEPROP 0 LAST CDS_SEC 1
J 0
(-4975 1950);
DISPLAY 0.680851 (-4975 1950);
DISPLAY INVISIBLE (-4975 1950);
FORCEPROP 1 LASTPIN (-4900 2000) $PN 1
J 2
(-4905 1962);
DISPLAY 0.787234 (-4905 1962);
PAINT MONO (-4905 1962);
FORCEPROP 1 LASTPIN (-4900 1800) $PN 2
J 2
(-4905 1810);
DISPLAY 0.787234 (-4905 1810);
PAINT MONO (-4905 1810);
FORCEPROP 1 LAST VALUE 49.9
J 2
(-4725 1875);
DISPLAY 0.638298 (-4725 1875);
FORCEPROP 1 LAST TOLERANCE 1%
J 2
(-4945 1925);
DISPLAY 0.978723 (-4945 1925);
DISPLAY INVISIBLE (-4945 1925);
FORCEPROP 1 LAST WATTAGE 1/16W
J 2
(-4940 1875);
DISPLAY 0.978723 (-4940 1875);
DISPLAY INVISIBLE (-4940 1875);
FORCEPROP 1 LAST PACK_TYPE 0402LF
J 2
(-4940 1725);
DISPLAY 0.978723 (-4940 1725);
DISPLAY INVISIBLE (-4940 1725);
FORCEPROP 1 LAST MATERIAL CHIP
J 2
(-4940 1825);
DISPLAY 0.978723 (-4940 1825);
DISPLAY INVISIBLE (-4940 1825);
FORCEPROP 2 LAST CDS_LIB pure_quanta
J 0
(-4900 1900);
DISPLAY INVISIBLE (-4900 1900);
FORCEPROP 1 LAST PATH I386
J 2
(-4950 2075);
DISPLAY 0.978723 (-4950 2075);
PAINT WHITE (-4950 2075);
DISPLAY INVISIBLE (-4950 2075);
FORCEPROP 1 LAST PART_NUMBER CS04992FB07
J 2
(-4940 1775);
DISPLAY 0.978723 (-4940 1775);
DISPLAY INVISIBLE (-4940 1775);
FORCEADD UNIVERSAL_GND..1
(-7400 5150);
FORCEPROP 3 LASTPIN (-7400 5200) SIG_NAME GND\g
J 0
(-7390 5210);
DISPLAY 0.659574 (-7390 5210);
PAINT MONO (-7390 5210);
DISPLAY INVISIBLE (-7390 5210);
FORCEPROP 2 LAST CDS_LIB pure_quanta_power
J 0
(-7400 5150);
DISPLAY INVISIBLE (-7400 5150);
FORCEPROP 1 LAST HDL_POWER GND
J 1
(-7375 5075);
DISPLAY 0.872340 (-7375 5075);
PAINT GREEN (-7375 5075);
DISPLAY INVISIBLE (-7375 5075);
FORCEPROP 1 LAST PATH I387
J 0
(-7325 5150);
DISPLAY 0.872340 (-7325 5150);
PAINT AQUA (-7325 5150);
DISPLAY INVISIBLE (-7325 5150);
FORCEADD Q_CAP..1
(-7400 5350);
FORCEPROP 1 LAST LOCATION C5024
J 0
(-7350 5450);
DISPLAY 0.489362 (-7350 5450);
PAINT SKYBLUE (-7350 5450);
FORCEPROP 0 LAST $SEC 1
J 0
(-7350 5475);
DISPLAY 0.680851 (-7350 5475);
PAINT MONO (-7350 5475);
DISPLAY INVISIBLE (-7350 5475);
FORCEPROP 0 LAST CDS_SEC 1
J 0
(-7350 5475);
DISPLAY 1.021277 (-7350 5475);
DISPLAY INVISIBLE (-7350 5475);
FORCEPROP 1 LASTPIN (-7400 5450) $PN 1
J 0
(-7390 5430);
DISPLAY 0.489362 (-7390 5430);
PAINT MONO (-7390 5430);
FORCEPROP 1 LASTPIN (-7400 5250) $PN 2
J 0
(-7390 5230);
DISPLAY 0.489362 (-7390 5230);
PAINT MONO (-7390 5230);
FORCEPROP 1 LAST PACK_TYPE 0402
J 0
(-7350 5150);
DISPLAY 0.489362 (-7350 5150);
PAINT SKYBLUE (-7350 5150);
FORCEPROP 1 LAST MATERIAL X7R
J 0
(-7350 5250);
DISPLAY 0.489362 (-7350 5250);
PAINT SKYBLUE (-7350 5250);
FORCEPROP 1 LAST TOLERANCE 5%
J 0
(-7350 5300);
DISPLAY 0.489362 (-7350 5300);
PAINT SKYBLUE (-7350 5300);
FORCEPROP 1 LAST VOLTAGE 50V
J 0
(-7350 5350);
DISPLAY 0.489362 (-7350 5350);
PAINT SKYBLUE (-7350 5350);
FORCEPROP 1 LAST VALUE 1000PF
J 0
(-7350 5400);
DISPLAY 0.489362 (-7350 5400);
PAINT SKYBLUE (-7350 5400);
FORCEPROP 2 LAST CDS_LIB pure_quanta
J 0
(-7400 5350);
DISPLAY INVISIBLE (-7400 5350);
FORCEPROP 1 LAST PATH I388
J 0
(-7350 5500);
DISPLAY 0.978723 (-7350 5500);
PAINT WHITE (-7350 5500);
DISPLAY INVISIBLE (-7350 5500);
FORCEPROP 1 LAST PART_NUMBER TMP_QCH21006JB10
J 0
(-7350 5200);
DISPLAY 0.489362 (-7350 5200);
PAINT SKYBLUE (-7350 5200);
DISPLAY INVISIBLE (-7350 5200);
FORCEADD Q_RES..1
(-3625 1450);
FORCEPROP 1 LAST LOCATION R572
J 0
(-3675 1500);
DISPLAY 0.638298 (-3675 1500);
FORCEPROP 2 LAST SEC 1
J 0
(-3675 1650);
DISPLAY 0.680851 (-3675 1650);
PAINT MONO (-3675 1650);
DISPLAY INVISIBLE (-3675 1650);
FORCEPROP 1 LASTPIN (-3725 1450) $PN 1
J 0
(-3713 1462);
DISPLAY 0.787234 (-3713 1462);
PAINT MONO (-3713 1462);
FORCEPROP 1 LASTPIN (-3525 1450) $PN 2
J 0
(-3563 1462);
DISPLAY 0.787234 (-3563 1462);
PAINT MONO (-3563 1462);
FORCEPROP 1 LAST MATERIAL CHIP
J 0
(-3625 1300);
DISPLAY 0.638298 (-3625 1300);
FORCEPROP 1 LAST WATTAGE 1/16W
J 2
(-3650 1300);
DISPLAY 0.638298 (-3650 1300);
FORCEPROP 1 LAST PACK_TYPE 0402LF
J 0
(-3375 1300);
DISPLAY 0.638298 (-3375 1300);
FORCEPROP 1 LAST VALUE 20M
J 2
(-3650 1350);
DISPLAY 0.638298 (-3650 1350);
FORCEPROP 1 LAST TOLERANCE 1%
J 0
(-3625 1350);
DISPLAY 0.638298 (-3625 1350);
FORCEPROP 2 LAST CDS_LIB pure_quanta
J 0
(-3625 1450);
DISPLAY INVISIBLE (-3625 1450);
FORCEPROP 2 LAST SEC_TYPE 0402LF
J 0
(-3675 1650);
DISPLAY 0.680851 (-3675 1650);
DISPLAY INVISIBLE (-3675 1650);
FORCEPROP 1 LAST PATH I389
J 0
(-3675 1600);
DISPLAY 0.978723 (-3675 1600);
PAINT WHITE (-3675 1600);
DISPLAY INVISIBLE (-3675 1600);
FORCEPROP 1 LAST PART_NUMBER CS62002FB01
J 0
(-3675 1550);
DISPLAY 0.638298 (-3675 1550);
DISPLAY INVISIBLE (-3675 1550);
FORCEADD Q_RES..1
R 2
(-8625 1950);
FORCEPROP 1 LAST LOCATION R558
J 2
(-8275 1950);
DISPLAY 0.510638 (-8275 1950);
FORCEPROP 2 LAST SEC 1
J 2
(-8575 2150);
DISPLAY 0.680851 (-8575 2150);
PAINT MONO (-8575 2150);
DISPLAY INVISIBLE (-8575 2150);
FORCEPROP 1 LASTPIN (-8525 1950) $PN 1
J 2
(-8537 1962);
DISPLAY 0.510638 (-8537 1962);
PAINT MONO (-8537 1962);
FORCEPROP 1 LASTPIN (-8725 1950) $PN 2
J 2
(-8687 1962);
DISPLAY 0.510638 (-8687 1962);
PAINT MONO (-8687 1962);
FORCEPROP 1 LAST VALUE 4.7K
J 0
(-8875 1950);
DISPLAY 0.510638 (-8875 1950);
FORCEPROP 1 LAST MATERIAL EMPTY
J 2
(-8400 1950);
DISPLAY 0.510638 (-8400 1950);
PAINT RED (-8400 1950);
FORCEPROP 1 LAST WATTAGE 1/16W
J 0
(-8600 1800);
DISPLAY 0.510638 (-8600 1800);
DISPLAY INVISIBLE (-8600 1800);
FORCEPROP 1 LAST TOLERANCE 5%
J 2
(-8625 1850);
DISPLAY 0.510638 (-8625 1850);
DISPLAY INVISIBLE (-8625 1850);
FORCEPROP 2 LAST CDS_LIB pure_quanta
J 2
(-8625 1950);
DISPLAY INVISIBLE (-8625 1950);
FORCEPROP 2 LAST SEC_TYPE 0402LF
J 2
(-8575 2150);
DISPLAY 0.680851 (-8575 2150);
DISPLAY INVISIBLE (-8575 2150);
FORCEPROP 1 LAST PACK_TYPE 0402LF
J 2
(-8875 1800);
DISPLAY 0.510638 (-8875 1800);
DISPLAY INVISIBLE (-8875 1800);
FORCEPROP 1 LAST PATH I390
J 2
(-8575 2100);
DISPLAY 0.978723 (-8575 2100);
PAINT WHITE (-8575 2100);
DISPLAY INVISIBLE (-8575 2100);
FORCEPROP 1 LAST PART_NUMBER CS24702JB10
J 2
(-8575 2050);
DISPLAY 0.638298 (-8575 2050);
DISPLAY INVISIBLE (-8575 2050);
FORCEADD OFFPAGE..2
(-7625 600);
FORCEPROP 2 LAST $XR1 81 
J 0
(-7346 600);
DISPLAY 0.638298 (-7346 600);
PAINT MONO (-7346 600);
FORCEPROP 2 LAST $XR0 55 
J 0
(-7436 600);
DISPLAY 0.638298 (-7436 600);
PAINT MONO (-7436 600);
FORCEPROP 2 LAST CDS_LIB standard
J 0
(-7625 600);
DISPLAY INVISIBLE (-7625 600);
FORCEPROP 1 LAST OFFPAGE TRUE
J 0
(-7300 475);
DISPLAY 0.872340 (-7300 475);
PAINT GREEN (-7300 475);
DISPLAY INVISIBLE (-7300 475);
FORCEPROP 1 LAST COMMENT_BODY TRUE
J 0
(-7670 505);
DISPLAY 0.872340 (-7670 505);
PAINT GREEN (-7670 505);
DISPLAY INVISIBLE (-7670 505);
FORCEPROP 2 LAST PATH I391
J 0
(-7450 675);
DISPLAY 0.680851 (-7450 675);
DISPLAY INVISIBLE (-7450 675);
FORCEADD Q_RES..2
(-8275 475);
FORCEPROP 1 LAST LOCATION R6503
J 0
(-8225 475);
DISPLAY 0.510638 (-8225 475);
FORCEPROP 0 LAST $SEC 1
J 0
(-8225 500);
DISPLAY 0.680851 (-8225 500);
PAINT MONO (-8225 500);
DISPLAY INVISIBLE (-8225 500);
FORCEPROP 0 LAST CDS_SEC 1
J 0
(-8225 500);
DISPLAY 0.680851 (-8225 500);
DISPLAY INVISIBLE (-8225 500);
FORCEPROP 1 LASTPIN (-8275 575) $PN 1
J 0
(-8270 537);
DISPLAY 0.787234 (-8270 537);
PAINT MONO (-8270 537);
FORCEPROP 1 LASTPIN (-8275 375) $PN 2
J 0
(-8270 385);
DISPLAY 0.787234 (-8270 385);
PAINT MONO (-8270 385);
FORCEPROP 1 LAST VALUE 2.2K
J 0
(-8225 450);
DISPLAY 0.510638 (-8225 450);
FORCEPROP 1 LAST MATERIAL CHIP
J 0
(-8225 425);
DISPLAY 0.510638 (-8225 425);
FORCEPROP 1 LAST PACK_TYPE 0402LF
J 0
(-8225 375);
DISPLAY 0.510638 (-8225 375);
FORCEPROP 1 LAST TOLERANCE 5%
J 0
(-8225 525);
DISPLAY 0.638298 (-8225 525);
DISPLAY INVISIBLE (-8225 525);
FORCEPROP 1 LAST WATTAGE 1/16W
J 0
(-8235 450);
DISPLAY 0.638298 (-8235 450);
DISPLAY INVISIBLE (-8235 450);
FORCEPROP 2 LAST CDS_LIB pure_quanta
J 0
(-8275 475);
DISPLAY INVISIBLE (-8275 475);
FORCEPROP 1 LAST PATH I392
J 0
(-8225 650);
DISPLAY 0.978723 (-8225 650);
PAINT WHITE (-8225 650);
DISPLAY INVISIBLE (-8225 650);
FORCEPROP 1 LAST PART_NUMBER CS22202JB07
J 0
(-8225 400);
DISPLAY 0.510638 (-8225 400);
DISPLAY INVISIBLE (-8225 400);
FORCEADD UNIVERSAL_GND..1
(-8275 225);
FORCEPROP 3 LASTPIN (-8275 275) SIG_NAME GND\g
J 0
(-8265 285);
DISPLAY 0.659574 (-8265 285);
PAINT MONO (-8265 285);
DISPLAY INVISIBLE (-8265 285);
FORCEPROP 2 LAST CDS_LIB pure_quanta_power
J 0
(-8275 225);
DISPLAY INVISIBLE (-8275 225);
FORCEPROP 1 LAST HDL_POWER GND
J 1
(-8250 150);
DISPLAY 0.872340 (-8250 150);
PAINT GREEN (-8250 150);
DISPLAY INVISIBLE (-8250 150);
FORCEPROP 1 LAST PATH I393
J 0
(-8200 225);
DISPLAY 0.872340 (-8200 225);
PAINT AQUA (-8200 225);
DISPLAY INVISIBLE (-8200 225);
FORCEADD Q_RES..1
(-2000 3825);
FORCEPROP 1 LAST LOCATION R8351
J 0
(-2175 3825);
DISPLAY 0.510638 (-2175 3825);
FORCEPROP 0 LAST $SEC 1
J 0
(-1575 3850);
DISPLAY 0.680851 (-1575 3850);
PAINT MONO (-1575 3850);
DISPLAY INVISIBLE (-1575 3850);
FORCEPROP 0 LAST CDS_SEC 1
J 0
(-1575 3850);
DISPLAY 0.680851 (-1575 3850);
DISPLAY INVISIBLE (-1575 3850);
FORCEPROP 1 LASTPIN (-2100 3825) $PN 1
J 0
(-2088 3837);
DISPLAY 0.787234 (-2088 3837);
PAINT MONO (-2088 3837);
FORCEPROP 1 LASTPIN (-1900 3825) $PN 2
J 0
(-1938 3837);
DISPLAY 0.787234 (-1938 3837);
PAINT MONO (-1938 3837);
FORCEPROP 1 LAST TOLERANCE 5%
J 0
(-1825 3825);
DISPLAY 0.510638 (-1825 3825);
FORCEPROP 1 LAST VALUE 0
J 2
(-1875 3825);
DISPLAY 0.510638 (-1875 3825);
FORCEPROP 1 LAST WATTAGE 1/16W
J 2
(-1575 3825);
DISPLAY 0.510638 (-1575 3825);
FORCEPROP 1 LAST PACK_TYPE 0402LF
J 0
(-2350 3825);
DISPLAY 0.510638 (-2350 3825);
FORCEPROP 2 LAST CDS_LIB pure_quanta
J 0
(-2000 3825);
DISPLAY INVISIBLE (-2000 3825);
FORCEPROP 1 LAST MATERIAL CHIP
J 0
(-2275 3875);
DISPLAY 0.510638 (-2275 3875);
DISPLAY INVISIBLE (-2275 3875);
FORCEPROP 1 LAST PATH I394
J 0
(-2050 3975);
DISPLAY 0.978723 (-2050 3975);
PAINT WHITE (-2050 3975);
DISPLAY INVISIBLE (-2050 3975);
FORCEPROP 1 LAST PART_NUMBER CS00002JB13
J 0
(-2125 3875);
DISPLAY 0.510638 (-2125 3875);
DISPLAY INVISIBLE (-2125 3875);
FORCEADD OFFPAGE..2
(-675 3875);
FORCEPROP 2 LAST $XR0 183 
J 0
(-486 3875);
DISPLAY 0.638298 (-486 3875);
PAINT MONO (-486 3875);
FORCEPROP 2 LAST CDS_LIB standard
J 0
(-675 3875);
DISPLAY INVISIBLE (-675 3875);
FORCEPROP 1 LAST OFFPAGE TRUE
J 0
(-350 3750);
DISPLAY 0.872340 (-350 3750);
PAINT GREEN (-350 3750);
DISPLAY INVISIBLE (-350 3750);
FORCEPROP 1 LAST COMMENT_BODY TRUE
J 0
(-720 3780);
DISPLAY 0.872340 (-720 3780);
PAINT GREEN (-720 3780);
DISPLAY INVISIBLE (-720 3780);
FORCEPROP 2 LAST PATH I395
J 0
(-475 3925);
DISPLAY 0.680851 (-475 3925);
DISPLAY INVISIBLE (-475 3925);
FORCEADD OFFPAGE..2
(-675 3825);
FORCEPROP 2 LAST $XR0 183 
J 0
(-486 3825);
DISPLAY 0.638298 (-486 3825);
PAINT MONO (-486 3825);
FORCEPROP 2 LAST CDS_LIB standard
J 0
(-675 3825);
DISPLAY INVISIBLE (-675 3825);
FORCEPROP 1 LAST OFFPAGE TRUE
J 0
(-350 3700);
DISPLAY 0.872340 (-350 3700);
PAINT GREEN (-350 3700);
DISPLAY INVISIBLE (-350 3700);
FORCEPROP 1 LAST COMMENT_BODY TRUE
J 0
(-720 3730);
DISPLAY 0.872340 (-720 3730);
PAINT GREEN (-720 3730);
DISPLAY INVISIBLE (-720 3730);
FORCEPROP 2 LAST PATH I396
J 0
(-475 3875);
DISPLAY 0.680851 (-475 3875);
DISPLAY INVISIBLE (-475 3875);
FORCEADD Q_RES..1
(-2000 3875);
FORCEPROP 1 LAST LOCATION R8350
J 0
(-2175 3875);
DISPLAY 0.510638 (-2175 3875);
FORCEPROP 0 LAST $SEC 1
J 0
(-2125 3950);
DISPLAY 0.680851 (-2125 3950);
PAINT MONO (-2125 3950);
DISPLAY INVISIBLE (-2125 3950);
FORCEPROP 0 LAST CDS_SEC 1
J 0
(-2125 3950);
DISPLAY 0.680851 (-2125 3950);
DISPLAY INVISIBLE (-2125 3950);
FORCEPROP 1 LASTPIN (-2100 3875) $PN 1
J 0
(-2088 3887);
DISPLAY 0.787234 (-2088 3887);
PAINT MONO (-2088 3887);
FORCEPROP 1 LASTPIN (-1900 3875) $PN 2
J 0
(-1938 3887);
DISPLAY 0.787234 (-1938 3887);
PAINT MONO (-1938 3887);
FORCEPROP 1 LAST VALUE 0
J 2
(-1875 3875);
DISPLAY 0.510638 (-1875 3875);
FORCEPROP 1 LAST MATERIAL CHIP
J 0
(-2275 3925);
DISPLAY 0.510638 (-2275 3925);
FORCEPROP 1 LAST WATTAGE 1/16W
J 2
(-1575 3875);
DISPLAY 0.510638 (-1575 3875);
FORCEPROP 1 LAST PACK_TYPE 0402LF
J 0
(-2350 3875);
DISPLAY 0.510638 (-2350 3875);
FORCEPROP 1 LAST TOLERANCE 5%
J 0
(-1825 3875);
DISPLAY 0.510638 (-1825 3875);
FORCEPROP 2 LAST CDS_LIB pure_quanta
J 0
(-2000 3875);
DISPLAY INVISIBLE (-2000 3875);
FORCEPROP 1 LAST PATH I397
J 0
(-2050 4025);
DISPLAY 0.978723 (-2050 4025);
PAINT WHITE (-2050 4025);
DISPLAY INVISIBLE (-2050 4025);
FORCEPROP 1 LAST PART_NUMBER CS00002JB13
J 0
(-2125 3925);
DISPLAY 0.510638 (-2125 3925);
DISPLAY INVISIBLE (-2125 3925);
FORCEADD OFFPAGE..2
R 2
(-6650 3225);
FORCEPROP 2 LAST $XR1 82 
J 0
(-6964 3225);
DISPLAY 0.638298 (-6964 3225);
PAINT MONO (-6964 3225);
FORCEPROP 2 LAST $XR0 55 
J 0
(-6874 3225);
DISPLAY 0.638298 (-6874 3225);
PAINT MONO (-6874 3225);
FORCEPROP 2 LAST CDS_LIB standard
J 0
(-6650 3225);
DISPLAY INVISIBLE (-6650 3225);
FORCEPROP 1 LAST OFFPAGE TRUE
J 2
(-6975 3100);
DISPLAY 0.872340 (-6975 3100);
PAINT GREEN (-6975 3100);
DISPLAY INVISIBLE (-6975 3100);
FORCEPROP 1 LAST COMMENT_BODY TRUE
J 2
(-6605 3130);
DISPLAY 0.872340 (-6605 3130);
PAINT GREEN (-6605 3130);
DISPLAY INVISIBLE (-6605 3130);
FORCEPROP 2 LAST PATH I398
J 0
(-6600 3300);
DISPLAY 0.680851 (-6600 3300);
DISPLAY INVISIBLE (-6600 3300);
FORCEADD UNIVERSAL_GND..1
(-4125 650);
FORCEPROP 3 LASTPIN (-4125 700) SIG_NAME GND\g
J 0
(-4115 710);
DISPLAY 0.659574 (-4115 710);
PAINT MONO (-4115 710);
DISPLAY INVISIBLE (-4115 710);
FORCEPROP 2 LAST CDS_LIB pure_quanta_power
J 0
(-4125 650);
DISPLAY INVISIBLE (-4125 650);
FORCEPROP 1 LAST HDL_POWER GND
J 1
(-4100 575);
DISPLAY 0.872340 (-4100 575);
PAINT GREEN (-4100 575);
DISPLAY INVISIBLE (-4100 575);
FORCEPROP 1 LAST PATH I4
J 0
(-4050 650);
DISPLAY 0.872340 (-4050 650);
PAINT AQUA (-4050 650);
DISPLAY INVISIBLE (-4050 650);
FORCEADD Q_CAP..1
(-4125 1050);
FORCEPROP 1 LAST LOCATION C238
J 0
(-4075 1150);
DISPLAY 0.489362 (-4075 1150);
PAINT SKYBLUE (-4075 1150);
FORCEPROP 0 LAST $SEC 1
J 0
(-4075 1200);
DISPLAY 0.680851 (-4075 1200);
PAINT MONO (-4075 1200);
DISPLAY INVISIBLE (-4075 1200);
FORCEPROP 0 LAST CDS_SEC 1
J 0
(-4075 1200);
DISPLAY 1.021277 (-4075 1200);
DISPLAY INVISIBLE (-4075 1200);
FORCEPROP 1 LASTPIN (-4125 1150) $PN 1
J 0
(-4115 1130);
DISPLAY 0.489362 (-4115 1130);
PAINT MONO (-4115 1130);
FORCEPROP 1 LASTPIN (-4125 950) $PN 2
J 0
(-4115 930);
DISPLAY 0.489362 (-4115 930);
PAINT MONO (-4115 930);
FORCEPROP 1 LAST TOLERANCE 1%
J 0
(-4075 1000);
DISPLAY 0.489362 (-4075 1000);
PAINT SKYBLUE (-4075 1000);
FORCEPROP 1 LAST MATERIAL NPO
J 0
(-4075 950);
DISPLAY 0.489362 (-4075 950);
PAINT SKYBLUE (-4075 950);
FORCEPROP 1 LAST PACK_TYPE 0402
J 0
(-4075 850);
DISPLAY 0.489362 (-4075 850);
PAINT SKYBLUE (-4075 850);
FORCEPROP 1 LAST VALUE 10PF
J 0
(-4075 1100);
DISPLAY 0.489362 (-4075 1100);
PAINT SKYBLUE (-4075 1100);
FORCEPROP 1 LAST VOLTAGE 50V
J 0
(-4075 1050);
DISPLAY 0.489362 (-4075 1050);
PAINT SKYBLUE (-4075 1050);
FORCEPROP 2 LAST CDS_LIB pure_quanta
J 0
(-4125 1050);
DISPLAY INVISIBLE (-4125 1050);
FORCEPROP 1 LAST PATH I5
J 0
(-4075 1200);
DISPLAY 0.978723 (-4075 1200);
PAINT WHITE (-4075 1200);
DISPLAY INVISIBLE (-4075 1200);
FORCEPROP 1 LAST PART_NUMBER TMP_QCH0106F0B00
J 0
(-4075 900);
DISPLAY 0.489362 (-4075 900);
PAINT SKYBLUE (-4075 900);
DISPLAY INVISIBLE (-4075 900);
FORCEADD Q_CRYSTAL..1
(-3625 1750);
FORCEPROP 1 LAST LOCATION Y5
J 0
(-3700 1950);
DISPLAY 0.489362 (-3700 1950);
PAINT SKYBLUE (-3700 1950);
FORCEPROP 0 LAST $SEC 1
J 0
(-3700 2100);
DISPLAY 0.680851 (-3700 2100);
PAINT MONO (-3700 2100);
DISPLAY INVISIBLE (-3700 2100);
FORCEPROP 0 LAST CDS_SEC 1
J 0
(-3700 2100);
DISPLAY 1.021277 (-3700 2100);
DISPLAY INVISIBLE (-3700 2100);
FORCEPROP 0 LASTPIN (-3725 1750) $PN 1
J 2
(-3735 1760);
DISPLAY 0.489362 (-3735 1760);
PAINT MONO (-3735 1760);
FORCEPROP 0 LASTPIN (-3525 1750) $PN 2
J 0
(-3515 1760);
DISPLAY 0.489362 (-3515 1760);
PAINT MONO (-3515 1760);
FORCEPROP 1 LAST MATERIAL EMPTY
J 0
(-3700 1850);
DISPLAY 0.489362 (-3700 1850);
PAINT RED (-3700 1850);
FORCEPROP 2 LAST VALUE 32.768KHZ
J 0
(-3700 2045);
DISPLAY 0.489362 (-3700 2045);
PAINT SKYBLUE (-3700 2045);
FORCEPROP 2 LAST PACK_TYPE SMLF
J 0
(-3700 1995);
DISPLAY 0.489362 (-3700 1995);
PAINT SKYBLUE (-3700 1995);
FORCEPROP 2 LAST CDS_LIB pure_quanta
J 0
(-3625 1750);
DISPLAY INVISIBLE (-3625 1750);
FORCEPROP 1 LAST NEEDS_NO_SIZE TRUE
J 0
(-3625 1750);
DISPLAY 0.468085 (-3625 1750);
PAINT GREEN (-3625 1750);
DISPLAY INVISIBLE (-3625 1750);
FORCEPROP 1 LAST PATH I7
J 0
(-3575 1835);
DISPLAY 0.723404 (-3575 1835);
PAINT GREEN (-3575 1835);
DISPLAY INVISIBLE (-3575 1835);
FORCEPROP 1 LAST PART_NUMBER BG632768012
J 0
(-3700 1905);
DISPLAY 0.489362 (-3700 1905);
PAINT SKYBLUE (-3700 1905);
DISPLAY INVISIBLE (-3700 1905);
FORCEADD UNIVERSAL_GND..1
(-3075 675);
FORCEPROP 3 LASTPIN (-3075 725) SIG_NAME GND\g
J 0
(-3065 735);
DISPLAY 0.659574 (-3065 735);
PAINT MONO (-3065 735);
DISPLAY INVISIBLE (-3065 735);
FORCEPROP 2 LAST CDS_LIB pure_quanta_power
J 0
(-3075 675);
DISPLAY INVISIBLE (-3075 675);
FORCEPROP 1 LAST HDL_POWER GND
J 1
(-3050 600);
DISPLAY 0.872340 (-3050 600);
PAINT GREEN (-3050 600);
DISPLAY INVISIBLE (-3050 600);
FORCEPROP 1 LAST PATH I8
J 0
(-3000 675);
DISPLAY 0.872340 (-3000 675);
PAINT AQUA (-3000 675);
DISPLAY INVISIBLE (-3000 675);
FORCEADD Q_CAP..1
(-3075 1075);
FORCEPROP 1 LAST LOCATION C239
J 0
(-3025 1175);
DISPLAY 0.489362 (-3025 1175);
PAINT SKYBLUE (-3025 1175);
FORCEPROP 0 LAST $SEC 1
J 0
(-3025 1225);
DISPLAY 0.680851 (-3025 1225);
PAINT MONO (-3025 1225);
DISPLAY INVISIBLE (-3025 1225);
FORCEPROP 0 LAST CDS_SEC 1
J 0
(-3025 1225);
DISPLAY 1.021277 (-3025 1225);
DISPLAY INVISIBLE (-3025 1225);
FORCEPROP 1 LASTPIN (-3075 1175) $PN 1
J 0
(-3065 1155);
DISPLAY 0.489362 (-3065 1155);
PAINT MONO (-3065 1155);
FORCEPROP 1 LASTPIN (-3075 975) $PN 2
J 0
(-3065 955);
DISPLAY 0.489362 (-3065 955);
PAINT MONO (-3065 955);
FORCEPROP 1 LAST TOLERANCE 1%
J 0
(-3025 1025);
DISPLAY 0.489362 (-3025 1025);
PAINT SKYBLUE (-3025 1025);
FORCEPROP 1 LAST MATERIAL NPO
J 0
(-3025 975);
DISPLAY 0.489362 (-3025 975);
PAINT SKYBLUE (-3025 975);
FORCEPROP 1 LAST PACK_TYPE 0402
J 0
(-3025 875);
DISPLAY 0.489362 (-3025 875);
PAINT SKYBLUE (-3025 875);
FORCEPROP 1 LAST VOLTAGE 50V
J 0
(-3025 1075);
DISPLAY 0.489362 (-3025 1075);
PAINT SKYBLUE (-3025 1075);
FORCEPROP 1 LAST VALUE 10PF
J 0
(-3025 1125);
DISPLAY 0.489362 (-3025 1125);
PAINT SKYBLUE (-3025 1125);
FORCEPROP 2 LAST CDS_LIB pure_quanta
J 0
(-3075 1075);
DISPLAY INVISIBLE (-3075 1075);
FORCEPROP 1 LAST PATH I9
J 0
(-3025 1225);
DISPLAY 0.978723 (-3025 1225);
PAINT WHITE (-3025 1225);
DISPLAY INVISIBLE (-3025 1225);
FORCEPROP 1 LAST PART_NUMBER TMP_QCH0106F0B00
J 0
(-3025 925);
DISPLAY 0.489362 (-3025 925);
PAINT SKYBLUE (-3025 925);
DISPLAY INVISIBLE (-3025 925);
FORCEADD DNS..2
(-8575 1700);
PAINT RED (-8575 1700);
FORCEPROP 2 LAST CDS_LIB mstr_misc
J 0
(-8575 1700);
DISPLAY INVISIBLE (-8575 1700);
FORCEPROP 1 LAST COMMENT_BODY TRUE
J 0
(-8575 1700);
PAINT RED (-8575 1700);
DISPLAY INVISIBLE (-8575 1700);
FORCEADD DNS..2
(-8600 2000);
PAINT RED (-8600 2000);
FORCEPROP 2 LAST CDS_LIB mstr_misc
J 0
(-8600 2000);
DISPLAY INVISIBLE (-8600 2000);
FORCEPROP 1 LAST COMMENT_BODY TRUE
J 0
(-8600 2000);
PAINT RED (-8600 2000);
DISPLAY INVISIBLE (-8600 2000);
FORCEADD DNS..2
(-8600 2200);
PAINT RED (-8600 2200);
FORCEPROP 2 LAST CDS_LIB mstr_misc
J 0
(-8600 2200);
DISPLAY INVISIBLE (-8600 2200);
FORCEPROP 1 LAST COMMENT_BODY TRUE
J 0
(-8600 2200);
PAINT RED (-8600 2200);
DISPLAY INVISIBLE (-8600 2200);
FORCEADD DNS..2
(-9025 3000);
PAINT RED (-9025 3000);
FORCEPROP 2 LAST CDS_LIB mstr_misc
J 0
(-9025 3000);
DISPLAY INVISIBLE (-9025 3000);
FORCEPROP 1 LAST COMMENT_BODY TRUE
J 0
(-9025 3000);
PAINT RED (-9025 3000);
DISPLAY INVISIBLE (-9025 3000);
FORCEADD DNS..2
(-8850 3000);
PAINT RED (-8850 3000);
FORCEPROP 2 LAST CDS_LIB mstr_misc
J 0
(-8850 3000);
DISPLAY INVISIBLE (-8850 3000);
FORCEPROP 1 LAST COMMENT_BODY TRUE
J 0
(-8850 3000);
PAINT RED (-8850 3000);
DISPLAY INVISIBLE (-8850 3000);
FORCEADD DNS..2
(-8675 3000);
PAINT RED (-8675 3000);
FORCEPROP 2 LAST CDS_LIB mstr_misc
J 0
(-8675 3000);
DISPLAY INVISIBLE (-8675 3000);
FORCEPROP 1 LAST COMMENT_BODY TRUE
J 0
(-8675 3000);
PAINT RED (-8675 3000);
DISPLAY INVISIBLE (-8675 3000);
FORCEADD DNS..2
(-8500 3000);
PAINT RED (-8500 3000);
FORCEPROP 2 LAST CDS_LIB mstr_misc
J 0
(-8500 3000);
DISPLAY INVISIBLE (-8500 3000);
FORCEPROP 1 LAST COMMENT_BODY TRUE
J 0
(-8500 3000);
PAINT RED (-8500 3000);
DISPLAY INVISIBLE (-8500 3000);
FORCEADD DNS..2
(-6650 5750);
PAINT RED (-6650 5750);
FORCEPROP 2 LAST CDS_LIB mstr_misc
J 0
(-6650 5750);
DISPLAY INVISIBLE (-6650 5750);
FORCEPROP 1 LAST COMMENT_BODY TRUE
J 0
(-6650 5750);
PAINT RED (-6650 5750);
DISPLAY INVISIBLE (-6650 5750);
FORCEADD DNS..2
(-2225 2125);
PAINT RED (-2225 2125);
FORCEPROP 2 LAST CDS_LIB mstr_misc
J 0
(-2225 2125);
DISPLAY INVISIBLE (-2225 2125);
FORCEPROP 1 LAST COMMENT_BODY TRUE
R 1
J 0
(-2150 1900);
DISPLAY 0.872340 (-2150 1900);
PAINT GREEN (-2150 1900);
DISPLAY INVISIBLE (-2150 1900);
FORCEADD DNS..2
(-3625 1725);
PAINT RED (-3625 1725);
FORCEPROP 2 LAST CDS_LIB mstr_misc
J 0
(-3625 1725);
DISPLAY INVISIBLE (-3625 1725);
FORCEPROP 1 LAST COMMENT_BODY TRUE
R 1
J 0
(-3550 1500);
DISPLAY 0.872340 (-3550 1500);
PAINT GREEN (-3550 1500);
DISPLAY INVISIBLE (-3550 1500);
FORCEADD DNS..2
(-8450 1125);
PAINT RED (-8450 1125);
FORCEPROP 2 LAST BOM_COST OCP3.0 
J 0
(-8575 1250);
DISPLAY 0.680851 (-8575 1250);
DISPLAY INVISIBLE (-8575 1250);
FORCEPROP 2 LAST CDS_LIB mstr_misc
J 0
(-8450 1125);
DISPLAY INVISIBLE (-8450 1125);
FORCEPROP 1 LAST COMMENT_BODY TRUE
J 0
(-8450 1125);
DISPLAY 0.744681 (-8450 1125);
DISPLAY INVISIBLE (-8450 1125);
FORCEADD DNS..2
(-8450 400);
PAINT RED (-8450 400);
FORCEPROP 2 LAST CDS_LIB mstr_misc
J 0
(-8450 400);
DISPLAY INVISIBLE (-8450 400);
FORCEPROP 2 LAST BOM_COST OCP3.0 
J 0
(-8575 525);
DISPLAY 0.680851 (-8575 525);
DISPLAY INVISIBLE (-8575 525);
FORCEPROP 1 LAST COMMENT_BODY TRUE
J 0
(-8450 400);
DISPLAY 0.744681 (-8450 400);
DISPLAY INVISIBLE (-8450 400);
FORCEADD DNS..2
(-8675 1125);
PAINT RED (-8675 1125);
FORCEPROP 2 LAST CDS_LIB mstr_misc
J 0
(-8675 1125);
DISPLAY INVISIBLE (-8675 1125);
FORCEPROP 2 LAST BOM_COST OCP3.0 
J 0
(-8800 1250);
DISPLAY 0.680851 (-8800 1250);
DISPLAY INVISIBLE (-8800 1250);
FORCEPROP 1 LAST COMMENT_BODY TRUE
J 0
(-8675 1125);
DISPLAY 0.744681 (-8675 1125);
DISPLAY INVISIBLE (-8675 1125);
FORCEADD DNS..2
(-8675 425);
PAINT RED (-8675 425);
FORCEPROP 2 LAST BOM_COST OCP3.0 
J 0
(-8800 550);
DISPLAY 0.680851 (-8800 550);
DISPLAY INVISIBLE (-8800 550);
FORCEPROP 2 LAST CDS_LIB mstr_misc
J 0
(-8675 425);
DISPLAY INVISIBLE (-8675 425);
FORCEPROP 1 LAST COMMENT_BODY TRUE
J 0
(-8675 425);
DISPLAY 0.744681 (-8675 425);
DISPLAY INVISIBLE (-8675 425);
FORCEADD DNS..2
(-8825 425);
PAINT RED (-8825 425);
FORCEPROP 2 LAST BOM_COST OCP3.0 
J 0
(-8950 550);
DISPLAY 0.680851 (-8950 550);
DISPLAY INVISIBLE (-8950 550);
FORCEPROP 2 LAST CDS_LIB mstr_misc
J 0
(-8825 425);
DISPLAY INVISIBLE (-8825 425);
FORCEPROP 1 LAST COMMENT_BODY TRUE
J 0
(-8825 425);
DISPLAY 0.744681 (-8825 425);
DISPLAY INVISIBLE (-8825 425);
FORCEADD DNS..2
(-8950 425);
PAINT RED (-8950 425);
FORCEPROP 2 LAST BOM_COST OCP3.0 
J 0
(-9075 550);
DISPLAY 0.680851 (-9075 550);
DISPLAY INVISIBLE (-9075 550);
FORCEPROP 2 LAST CDS_LIB mstr_misc
J 0
(-8950 425);
DISPLAY INVISIBLE (-8950 425);
FORCEPROP 1 LAST COMMENT_BODY TRUE
J 0
(-8950 425);
DISPLAY 0.744681 (-8950 425);
DISPLAY INVISIBLE (-8950 425);
FORCEADD DNS..2
(-9075 425);
PAINT RED (-9075 425);
FORCEPROP 2 LAST BOM_COST OCP3.0 
J 0
(-9200 550);
DISPLAY 0.680851 (-9200 550);
DISPLAY INVISIBLE (-9200 550);
FORCEPROP 2 LAST CDS_LIB mstr_misc
J 0
(-9075 425);
DISPLAY INVISIBLE (-9075 425);
FORCEPROP 1 LAST COMMENT_BODY TRUE
J 0
(-9075 425);
DISPLAY 0.744681 (-9075 425);
DISPLAY INVISIBLE (-9075 425);
FORCEADD QUANTA_TITLE_BLOCK_C..1
(0 0);
FORCEPROP 0 LAST CDS_CON_LAST_MODIFIED Thu Sep 14 16:12:00 2023
J 0
(-1885 15);
DISPLAY INVISIBLE (-1885 15);
FORCEPROP 1 LAST CUSTOM_TXT_CDS <CON_LAST_MODIFIED>
J 0
(-1885 15);
DISPLAY 0.978723 (-1885 15);
FORCEPROP 2 LAST CUSTOM_TXT_CDS <XR_PAGE_TITLE>
J 0
(-7890 5250);
DISPLAY 0.638298 (-7890 5250);
PAINT PINK (-7890 5250);
DISPLAY INVISIBLE (-7890 5250);
FORCEPROP 1 LAST CUSTOM_TXT_CDS <NAME_2>
J 0
(-3175 50);
FORCEPROP 1 LAST CUSTOM_TXT_CDS <NAME_1>
J 0
(-3175 175);
FORCEPROP 1 LAST CUSTOM_TXT_CDS <Q_NUMBER>
J 0
(-1403 103);
DISPLAY 1.212766 (-1403 103);
FORCEPROP 1 LAST CUSTOM_TXT_CDS <Q_PROJ>
J 0
(-2382 102);
DISPLAY 1.212766 (-2382 102);
FORCEPROP 1 LAST CUSTOM_TXT_CDS <Q_REV>
J 0
(-184 103);
DISPLAY 1.212766 (-184 103);
FORCEPROP 1 LAST CUSTOM_TXT_CDS <CON_PAGE_NUM> OF <CON_TOTAL_PAGES>
J 0
(-446 18);
DISPLAY 0.978723 (-446 18);
FORCEPROP 1 LAST Q_TITLE CPU1 MISC 2/2
J 0
(-9275 50);
DISPLAY 2.446809 (-9275 50);
PAINT GREEN (-9275 50);
FORCEPROP 2 LAST CDS_LIB pure_quanta
J 0
(0 0);
DISPLAY INVISIBLE (0 0);
FORCEPROP 1 LAST CDS_LMAN_SYM_OUTLINE -9475,6775,100,-125
J 0
(0 0);
DISPLAY 0.468085 (0 0);
PAINT GREEN (0 0);
DISPLAY INVISIBLE (0 0);
FORCEPROP 2 LAST PAGE_BORDER TRUE
J 0
(-7890 5250);
DISPLAY 0.638298 (-7890 5250);
PAINT PINK (-7890 5250);
DISPLAY INVISIBLE (-7890 5250);
FORCEPROP 2 LAST CDS_XR_PAGE_TITLE CR-55 : @T6G_MB_LIB.T6G(SCH_1):PAGE55
J 0
(-7890 5250);
DISPLAY 0.638298 (-7890 5250);
PAINT PINK (-7890 5250);
DISPLAY INVISIBLE (-7890 5250);
FORCEPROP 1 LAST Q_DEPT BU9
J 1
(-3763 49);
DISPLAY 1.957447 (-3763 49);
PAINT GREEN (-3763 49);
DISPLAY INVISIBLE (-3763 49);
FORCEPROP 1 LAST COMMENT_BODY TRUE
J 0
(12 -13);
DISPLAY 0.978723 (12 -13);
PAINT GREEN (12 -13);
DISPLAY INVISIBLE (12 -13);
WIRE 16 -1 (-5800 1450)(-5900 1450);
WIRE 16 -1 (-5900 1450)(-5900 1300);
FORCEPROP 0 LAST VOLTAGE 0
J 0
(-5900 1125);
PAINT SKYBLUE (-5900 1125);
DISPLAY INVISIBLE (-5900 1125);
FORCEPROP 0 LAST $PHYS_NET_NAME GND
J 0
(-5900 1172);
DISPLAY INVISIBLE (-5900 1172);
WIRE 16 -1 (-5250 1450)(-5125 1450);
WIRE 16 -1 (-5125 1450)(-5125 1300);
WIRE 16 -1 (-4900 725)(-4900 575);
WIRE 16 -1 (-6175 725)(-6175 575);
WIRE 16 -1 (-7150 4875)(-7375 4875);
WIRE 16 -1 (-7375 4875)(-7375 4925);
WIRE 16 -1 (-7400 5250)(-7400 5200);
WIRE 16 -1 (-8275 375)(-8275 275);
WIRE 16 -1 (-4125 700)(-4125 950);
WIRE 16 -1 (-3075 725)(-3075 975);
WIRE 16 -1 (-7675 875)(-8975 875);
FORCEPROP 2 LAST SIG_NAME FM_BMC_READY_N
J 0
(-8325 885);
DISPLAY 0.553191 (-8325 885);
PAINT WHITE (-8325 885);
WIRE 16 -1 (-8975 875)(-8975 1050);
WIRE 16 -1 (-8975 525)(-8975 875);
WIRE 16 -1 (-8850 800)(-7675 800);
FORCEPROP 2 LAST SIG_NAME FM_BMC_TPM_PRES_N
J 0
(-8325 810);
DISPLAY 0.553191 (-8325 810);
PAINT WHITE (-8325 810);
WIRE 16 -1 (-8850 1050)(-8850 800);
WIRE 16 -1 (-8850 525)(-8850 800);
WIRE 16 -1 (-8700 750)(-7675 750);
FORCEPROP 2 LAST SIG_NAME CPU1_PWRGD_OUT
J 0
(-8325 760);
DISPLAY 0.489362 (-8325 760);
WIRE 16 -1 (-8700 750)(-8700 1050);
WIRE 16 -1 (-8700 525)(-8700 750);
WIRE 16 -1 (-7675 675)(-8475 675);
FORCEPROP 2 LAST SIG_NAME RST_CPU1_RSMRST_N
J 0
(-8325 685);
DISPLAY 0.489362 (-8325 685);
WIRE 16 -1 (-8475 1050)(-8475 675);
WIRE 16 -1 (-8475 525)(-8475 675);
WIRE 16 -1 (-6650 3125)(-5625 3125);
FORCEPROP 2 LAST SIG_NAME TP_SLOT2_BUF_SKU_ID1
J 0
(-6575 3135);
DISPLAY 0.489362 (-6575 3135);
FORCEPROP 2 LASTPROP $XRERR UNIQUE?
J 0
(-6890 3125);
DISPLAY 0.638298 (-6890 3125);
PAINT MONO (-6890 3125);
DISPLAY INVISIBLE (-6890 3125);
WIRE 16 -1 (-5425 1050)(-4900 1050);
WIRE 16 -1 (-4900 1650)(-4900 1050);
WIRE 16 -1 (-4900 1050)(-4900 925);
WIRE 16 -1 (-4900 1650)(-4900 1800);
WIRE 16 -1 (-5250 1650)(-4900 1650);
FORCEPROP 2 LAST SIG_NAME XTAL_CPU1_X48M_X2_R
J 0
(-5160 1685);
DISPLAY 0.489362 (-5160 1685);
FORCEPROP 2 LASTPROP $XRERR UNIQUE?
J 0
(-5400 1685);
DISPLAY 0.638298 (-5400 1685);
PAINT MONO (-5400 1685);
DISPLAY INVISIBLE (-5400 1685);
WIRE 16 -1 (-6175 2150)(-4550 2150);
FORCEPROP 2 LAST SIG_NAME XTAL_CPU1_X48M_X1
J 0
(-4960 2160);
DISPLAY 0.489362 (-4960 2160);
WIRE 16 -1 (-6175 1650)(-6175 2150);
WIRE 16 -1 (-5800 1650)(-6175 1650);
WIRE 16 -1 (-6175 1650)(-6175 1050);
WIRE 16 -1 (-5625 1050)(-6175 1050);
WIRE 16 -1 (-6175 1050)(-6175 925);
WIRE 16 -1 (-6600 3375)(-5625 3375);
FORCEPROP 2 LAST SIG_NAME IRQ_CPU_BMC_NMI_N
J 0
(-6575 3385);
DISPLAY 0.553191 (-6575 3385);
PAINT WHITE (-6575 3385);
WIRE 16 -1 (-6800 3475)(-5625 3475);
FORCEPROP 2 LAST SIG_NAME CPU1_SPD_HOST_CTRL_R_N
J 2
(-6135 3485);
DISPLAY 0.489362 (-6135 3485);
FORCEPROP 2 LASTPROP $XRERR UNIQUE?
J 0
(-6375 3485);
DISPLAY 0.638298 (-6375 3485);
PAINT MONO (-6375 3485);
DISPLAY INVISIBLE (-6375 3485);
WIRE 16 -1 (-7000 3475)(-7850 3475);
FORCEPROP 2 LAST SIG_NAME CPU1_SPD_HOST_CTRL_N
J 2
(-7310 3485);
DISPLAY 0.489362 (-7310 3485);
WIRE 16 -1 (-8525 2100)(-7675 2100);
FORCEPROP 2 LAST SIG_NAME CPU1_SPD_HOST_CTRL_N
J 0
(-8235 2110);
DISPLAY 0.489362 (-8235 2110);
WIRE 16 -1 (-3125 4425)(-2100 4425);
FORCEPROP 2 LAST SIG_NAME CLK_100M_CPU1_CLK04_R_DN
J 0
(-3035 4435);
DISPLAY 0.489362 (-3035 4435);
FORCEPROP 2 LASTPROP $XRERR UNIQUE?
J 0
(-3275 4435);
DISPLAY 0.638298 (-3275 4435);
PAINT MONO (-3275 4435);
DISPLAY INVISIBLE (-3275 4435);
WIRE 16 -1 (-1900 3825)(-725 3825);
FORCEPROP 2 LAST SIG_NAME CLK_100M_CPU1_CLK13_DN
J 0
(-1485 3835);
DISPLAY 0.489362 (-1485 3835);
WIRE 16 -1 (-1900 3875)(-725 3875);
FORCEPROP 2 LAST SIG_NAME CLK_100M_CPU1_CLK13_DP
J 0
(-1485 3885);
DISPLAY 0.489362 (-1485 3885);
WIRE 16 -1 (-1900 3975)(-725 3975);
FORCEPROP 2 LAST SIG_NAME CLK_100M_CPU1_CLK12_DN
J 0
(-1485 3985);
DISPLAY 0.489362 (-1485 3985);
WIRE 16 -1 (-3125 3825)(-2100 3825);
FORCEPROP 2 LAST SIG_NAME CLK_100M_CPU1_CLK13_R_DN
J 0
(-2985 3835);
DISPLAY 0.489362 (-2985 3835);
FORCEPROP 2 LASTPROP $XRERR UNIQUE?
J 0
(-3225 3835);
DISPLAY 0.638298 (-3225 3835);
PAINT MONO (-3225 3835);
DISPLAY INVISIBLE (-3225 3835);
WIRE 16 -1 (-3125 3875)(-2100 3875);
FORCEPROP 2 LAST SIG_NAME CLK_100M_CPU1_CLK13_R_DP
J 0
(-2985 3885);
DISPLAY 0.489362 (-2985 3885);
FORCEPROP 2 LASTPROP $XRERR UNIQUE?
J 0
(-3225 3885);
DISPLAY 0.638298 (-3225 3885);
PAINT MONO (-3225 3885);
DISPLAY INVISIBLE (-3225 3885);
WIRE 16 -1 (-1900 4125)(-725 4125);
FORCEPROP 2 LAST SIG_NAME CLK_100M_CPU1_CLK11_DN
J 0
(-1485 4135);
DISPLAY 0.489362 (-1485 4135);
WIRE 16 -1 (-1900 4275)(-725 4275);
FORCEPROP 2 LAST SIG_NAME CLK_100M_CPU1_CLK05_DN
J 0
(-1385 4285);
DISPLAY 0.489362 (-1385 4285);
WIRE 16 -1 (-1900 4175)(-725 4175);
FORCEPROP 2 LAST SIG_NAME CLK_100M_CPU1_CLK11_DP
J 0
(-1485 4185);
DISPLAY 0.489362 (-1485 4185);
WIRE 16 -1 (-3125 3975)(-2100 3975);
FORCEPROP 2 LAST SIG_NAME CLK_100M_CPU1_CLK12_R_DN
J 0
(-2985 3985);
DISPLAY 0.489362 (-2985 3985);
FORCEPROP 2 LASTPROP $XRERR UNIQUE?
J 0
(-3225 3985);
DISPLAY 0.638298 (-3225 3985);
PAINT MONO (-3225 3985);
DISPLAY INVISIBLE (-3225 3985);
WIRE 16 -1 (-3125 4025)(-2100 4025);
FORCEPROP 2 LAST SIG_NAME CLK_100M_CPU1_CLK12_R_DP
J 0
(-2985 4035);
DISPLAY 0.489362 (-2985 4035);
FORCEPROP 2 LASTPROP $XRERR UNIQUE?
J 0
(-3225 4035);
DISPLAY 0.638298 (-3225 4035);
PAINT MONO (-3225 4035);
DISPLAY INVISIBLE (-3225 4035);
WIRE 16 -1 (-3125 4125)(-2100 4125);
FORCEPROP 2 LAST SIG_NAME CLK_100M_CPU1_CLK11_R_DN
J 0
(-2985 4135);
DISPLAY 0.489362 (-2985 4135);
FORCEPROP 2 LASTPROP $XRERR UNIQUE?
J 0
(-3225 4135);
DISPLAY 0.638298 (-3225 4135);
PAINT MONO (-3225 4135);
DISPLAY INVISIBLE (-3225 4135);
WIRE 16 -1 (-3125 4175)(-2100 4175);
FORCEPROP 2 LAST SIG_NAME CLK_100M_CPU1_CLK11_R_DP
J 0
(-2985 4185);
DISPLAY 0.489362 (-2985 4185);
FORCEPROP 2 LASTPROP $XRERR UNIQUE?
J 0
(-3225 4185);
DISPLAY 0.638298 (-3225 4185);
PAINT MONO (-3225 4185);
DISPLAY INVISIBLE (-3225 4185);
WIRE 16 -1 (-9100 1250)(-9100 1275);
WIRE 16 -1 (-9100 1275)(-8975 1275);
WIRE 16 -1 (-8975 1275)(-8850 1275);
WIRE 16 -1 (-8975 1250)(-8975 1275);
WIRE 16 -1 (-8850 1275)(-8700 1275);
WIRE 16 -1 (-8850 1250)(-8850 1275);
WIRE 16 -1 (-8700 1275)(-8475 1275);
WIRE 16 -1 (-8700 1250)(-8700 1275);
WIRE 16 -1 (-8700 1275)(-8700 1300);
WIRE 16 -1 (-8475 1275)(-8475 1250);
WIRE 16 -1 (-8725 2250)(-8975 2250);
WIRE 16 -1 (-8975 2450)(-8975 2250);
WIRE 16 -1 (-8975 2250)(-8975 2200);
WIRE 16 -1 (-8725 2200)(-8975 2200);
WIRE 16 -1 (-8975 2200)(-8975 2150);
WIRE 16 -1 (-8725 2150)(-8975 2150);
WIRE 16 -1 (-8975 2150)(-8975 2100);
WIRE 16 -1 (-8725 2100)(-8975 2100);
WIRE 16 -1 (-8975 2050)(-8975 2100);
WIRE 16 -1 (-8725 2050)(-8975 2050);
WIRE 16 -1 (-8975 2000)(-8975 2050);
WIRE 16 -1 (-8725 2000)(-8975 2000);
WIRE 16 -1 (-8975 2000)(-8975 1950);
WIRE 16 -1 (-8725 1950)(-8975 1950);
WIRE 16 -1 (-8975 1900)(-8975 1950);
WIRE 16 -1 (-8725 1900)(-8975 1900);
WIRE 16 -1 (-8975 1900)(-8975 1850);
WIRE 16 -1 (-8725 1850)(-8975 1850);
WIRE 16 -1 (-8975 1850)(-8975 1700);
WIRE 16 -1 (-8725 1700)(-8975 1700);
WIRE 16 -1 (-8975 1700)(-8975 1650);
WIRE 16 -1 (-8725 1650)(-8975 1650);
WIRE 16 -1 (-8525 3100)(-8525 3150);
WIRE 16 -1 (-8525 3250)(-8525 3150);
WIRE 16 -1 (-8525 3150)(-8700 3150);
WIRE 16 -1 (-8700 3100)(-8700 3150);
WIRE 16 -1 (-8700 3150)(-8875 3150);
WIRE 16 -1 (-8875 3100)(-8875 3150);
WIRE 16 -1 (-8875 3150)(-9050 3150);
WIRE 16 -1 (-9050 3100)(-9050 3150);
WIRE 16 -1 (-1900 4025)(-725 4025);
FORCEPROP 2 LAST SIG_NAME CLK_100M_CPU1_CLK12_DP
J 0
(-1485 4035);
DISPLAY 0.489362 (-1485 4035);
WIRE 16 -1 (-3125 4275)(-2100 4275);
FORCEPROP 2 LAST SIG_NAME CLK_100M_CPU1_CLK05_R_DN
J 0
(-3035 4285);
DISPLAY 0.489362 (-3035 4285);
FORCEPROP 2 LASTPROP $XRERR UNIQUE?
J 0
(-3275 4285);
DISPLAY 0.638298 (-3275 4285);
PAINT MONO (-3275 4285);
DISPLAY INVISIBLE (-3275 4285);
WIRE 16 -1 (-1900 4325)(-725 4325);
FORCEPROP 2 LAST SIG_NAME CLK_100M_CPU1_CLK05_DP
J 0
(-1385 4335);
DISPLAY 0.489362 (-1385 4335);
WIRE 16 -1 (-3125 4325)(-2100 4325);
FORCEPROP 2 LAST SIG_NAME CLK_100M_CPU1_CLK05_R_DP
J 0
(-3035 4335);
DISPLAY 0.489362 (-3035 4335);
FORCEPROP 2 LASTPROP $XRERR UNIQUE?
J 0
(-3275 4335);
DISPLAY 0.638298 (-3275 4335);
PAINT MONO (-3275 4335);
DISPLAY INVISIBLE (-3275 4335);
WIRE 16 -1 (-3125 4475)(-2100 4475);
FORCEPROP 2 LAST SIG_NAME CLK_100M_CPU1_CLK04_R_DP
J 0
(-3035 4485);
DISPLAY 0.489362 (-3035 4485);
FORCEPROP 2 LASTPROP $XRERR UNIQUE?
J 0
(-3275 4485);
DISPLAY 0.638298 (-3275 4485);
PAINT MONO (-3275 4485);
DISPLAY INVISIBLE (-3275 4485);
WIRE 16 -1 (-3125 4725)(-2100 4725);
FORCEPROP 2 LAST SIG_NAME CLK_100M_CPU1_CLK02_R_DN
J 0
(-3035 4735);
DISPLAY 0.489362 (-3035 4735);
FORCEPROP 2 LASTPROP $XRERR UNIQUE?
J 0
(-3275 4735);
DISPLAY 0.638298 (-3275 4735);
PAINT MONO (-3275 4735);
DISPLAY INVISIBLE (-3275 4735);
WIRE 16 -1 (-3125 4575)(-2100 4575);
FORCEPROP 2 LAST SIG_NAME CLK_100M_CPU1_CLK03_R_DN
J 0
(-3035 4585);
DISPLAY 0.489362 (-3035 4585);
FORCEPROP 2 LASTPROP $XRERR UNIQUE?
J 0
(-3275 4585);
DISPLAY 0.638298 (-3275 4585);
PAINT MONO (-3275 4585);
DISPLAY INVISIBLE (-3275 4585);
WIRE 16 -1 (-1900 4425)(-725 4425);
FORCEPROP 2 LAST SIG_NAME CLK_100M_CPU1_CLK04_DN
J 0
(-1385 4435);
DISPLAY 0.489362 (-1385 4435);
WIRE 16 -1 (-1900 4475)(-725 4475);
FORCEPROP 2 LAST SIG_NAME CLK_100M_CPU1_CLK04_DP
J 0
(-1385 4485);
DISPLAY 0.489362 (-1385 4485);
WIRE 16 -1 (-4900 2000)(-4900 2100);
FORCEPROP 2 LAST SIG_NAME XTAL_CPU1_X48M_X2
J 0
(-4960 2110);
DISPLAY 0.489362 (-4960 2110);
WIRE 16 -1 (-4900 2100)(-4550 2100);
WIRE 16 -1 (-7675 600)(-8275 600);
FORCEPROP 2 LAST SIG_NAME CPU1_FORCE_SELFREFRESH
J 0
(-8260 610);
DISPLAY 0.553191 (-8260 610);
WIRE 16 -1 (-8275 600)(-8275 575);
WIRE 16 -1 (-9100 1050)(-9100 950);
WIRE 16 -1 (-9100 950)(-7675 950);
FORCEPROP 2 LAST SIG_NAME IRQ_CPU_BMC_NMI_N
J 0
(-8325 960);
DISPLAY 0.553191 (-8325 960);
PAINT WHITE (-8325 960);
WIRE 16 -1 (-9100 525)(-9100 950);
WIRE 16 -1 (-7675 1950)(-8525 1950);
FORCEPROP 2 LAST SIG_NAME CPU1_FORCE_SELFREFRESH
J 0
(-8235 1960);
DISPLAY 0.489362 (-8235 1960);
WIRE 16 -1 (-7675 1850)(-8525 1850);
FORCEPROP 2 LAST SIG_NAME CPU1_NMI_SYNC_FLOOD_N
J 0
(-8235 1860);
DISPLAY 0.489362 (-8235 1860);
WIRE 16 -1 (-7675 2000)(-8525 2000);
FORCEPROP 2 LAST SIG_NAME RST_CPU1_RESETL_N
J 0
(-8235 2010);
DISPLAY 0.489362 (-8235 2010);
WIRE 16 -1 (-7675 1900)(-8525 1900);
FORCEPROP 2 LAST SIG_NAME RST_CPU1_SYS_N
J 0
(-8235 1910);
DISPLAY 0.489362 (-8235 1910);
WIRE 16 -1 (-8525 1700)(-7675 1700);
FORCEPROP 2 LAST SIG_NAME CPU1_SLP_S5_N
J 0
(-8235 1710);
DISPLAY 0.489362 (-8235 1710);
WIRE 16 -1 (-7675 2050)(-8525 2050);
FORCEPROP 2 LAST SIG_NAME CPU1_NV_SAVE_N
J 0
(-8235 2060);
DISPLAY 0.489362 (-8235 2060);
WIRE 16 -1 (-3125 5425)(-2350 5425);
FORCEPROP 2 LAST SIG_NAME CPU1_FORCE_SELFREFRESH
J 0
(-2885 5435);
DISPLAY 0.489362 (-2885 5435);
WIRE 16 -1 (-6375 3725)(-5625 3725);
FORCEPROP 2 LAST SIG_NAME CPU1_SMERR_N
J 0
(-6325 3735);
DISPLAY 0.489362 (-6325 3735);
WIRE 16 -1 (-6725 5725)(-7575 5725);
FORCEPROP 2 LAST SIG_NAME FM_CPU1_SLP_S3_N
J 0
(-7425 5735);
DISPLAY 0.489362 (-7425 5735);
WIRE 16 -1 (-5625 5725)(-6525 5725);
FORCEPROP 2 LAST SIG_NAME CPU1_SLP_S3_N
J 0
(-6350 5735);
DISPLAY 0.489362 (-6350 5735);
FORCEPROP 2 LASTPROP $XR0 55 
J 0
(-6620 5735);
DISPLAY 0.638298 (-6620 5735);
PAINT MONO (-6620 5735);
WIRE 16 -1 (-6725 5775)(-7575 5775);
FORCEPROP 2 LAST SIG_NAME FM_CPU1_SLP_S5_N
J 0
(-7425 5785);
DISPLAY 0.489362 (-7425 5785);
WIRE 16 -1 (-5625 5775)(-6525 5775);
FORCEPROP 2 LAST SIG_NAME CPU1_SLP_S5_N
J 0
(-6350 5785);
DISPLAY 0.489362 (-6350 5785);
FORCEPROP 2 LASTPROP $XR0 55 
J 0
(-6620 5785);
DISPLAY 0.638298 (-6620 5785);
PAINT MONO (-6620 5785);
WIRE 16 -1 (-2150 2125)(-1200 2125);
FORCEPROP 2 LAST SIG_NAME XTAL_CPU1_X32K_X2
J 0
(-1660 2135);
DISPLAY 0.489362 (-1660 2135);
WIRE 16 -1 (-1925 2175)(-1200 2175);
FORCEPROP 2 LAST SIG_NAME XTAL_CPU1_X32K_X1
J 0
(-1660 2185);
DISPLAY 0.489362 (-1660 2185);
WIRE 16 -1 (-1925 2175)(-1925 2425);
WIRE 16 -1 (-2150 2175)(-1925 2175);
WIRE 16 -1 (-1925 2425)(-2150 2425);
WIRE 16 -1 (-2350 2425)(-3075 2425);
FORCEPROP 2 LAST SIG_NAME CLK_CPU0_RTCCLK
J 0
(-2985 2435);
DISPLAY 0.489362 (-2985 2435);
WIRE 16 -1 (-7400 5525)(-5625 5525);
FORCEPROP 2 LAST SIG_NAME RST_CPU1_RSMRST_N
J 2
(-7035 5535);
DISPLAY 0.489362 (-7035 5535);
WIRE 16 -1 (-7400 5525)(-7400 5450);
WIRE 16 -1 (-7550 5525)(-7400 5525);
WIRE 16 -1 (-6375 5425)(-5625 5425);
FORCEPROP 2 LAST SIG_NAME CPU1_PWR_GD_IN
J 0
(-6310 5435);
DISPLAY 0.489362 (-6310 5435);
WIRE 16 -1 (-6950 4875)(-5625 4875);
FORCEPROP 2 LAST SIG_NAME INT_CPU1_HP_UBM_N
J 0
(-6325 4885);
DISPLAY 0.489362 (-6325 4885);
FORCEPROP 2 LASTPROP $XRERR UNIQUE?
J 0
(-6565 4885);
DISPLAY 0.638298 (-6565 4885);
PAINT MONO (-6565 4885);
DISPLAY INVISIBLE (-6565 4885);
WIRE 16 -1 (-6375 5225)(-5625 5225);
FORCEPROP 2 LAST SIG_NAME XTAL_CPU1_X48M_X2
J 0
(-6325 5235);
DISPLAY 0.489362 (-6325 5235);
WIRE 16 -1 (-2225 5975)(-3125 5975);
FORCEPROP 2 LAST SIG_NAME CLK_CPU1_RTCCLK
J 0
(-2900 5985);
DISPLAY 0.489362 (-2900 5985);
WIRE 16 -1 (-3125 5875)(-2225 5875);
FORCEPROP 2 LAST SIG_NAME RST_CPU1_RESETL_N
J 0
(-2900 5885);
DISPLAY 0.489362 (-2900 5885);
WIRE 16 -1 (-3125 5775)(-2225 5775);
FORCEPROP 2 LAST SIG_NAME PWRGD_CPU1_PWROK
J 0
(-2910 5785);
DISPLAY 0.489362 (-2910 5785);
WIRE 16 -1 (-3125 6075)(-2350 6075);
FORCEPROP 2 LAST SIG_NAME CLK_100M_REF_IN_DN
J 0
(-2900 6085);
DISPLAY 0.489362 (-2900 6085);
WIRE 16 -1 (-3125 6125)(-2350 6125);
FORCEPROP 2 LAST SIG_NAME CLK_100M_REF_IN_DP
J 0
(-2900 6135);
DISPLAY 0.489362 (-2900 6135);
WIRE 16 -1 (-3125 3175)(-2200 3175);
FORCEPROP 2 LAST SIG_NAME SMB_CPU1_SEC_SCL
J 2
(-2375 3185);
DISPLAY 0.489362 (-2375 3185);
WIRE 16 -1 (-3125 3125)(-2200 3125);
FORCEPROP 2 LAST SIG_NAME SMB_CPU1_SEC_SDA
J 2
(-2375 3135);
DISPLAY 0.489362 (-2375 3135);
WIRE 16 -1 (-6800 4275)(-5625 4275);
FORCEPROP 2 LAST SIG_NAME I3C_1_SPD_DDRGL_CPU1_R_SDA
J 2
(-5785 4285);
DISPLAY 0.489362 (-5785 4285);
WIRE 16 -1 (-6800 4325)(-5625 4325);
FORCEPROP 2 LAST SIG_NAME I3C_1_SPD_DDRGL_CPU1_R_SCL
J 2
(-5785 4335);
DISPLAY 0.489362 (-5785 4335);
WIRE 16 -1 (-6800 4375)(-5625 4375);
FORCEPROP 2 LAST SIG_NAME I3C_0_SPD_DDRAF_CPU1_R_SDA
J 2
(-5785 4385);
DISPLAY 0.489362 (-5785 4385);
WIRE 16 -1 (-6375 5075)(-5625 5075);
FORCEPROP 2 LAST SIG_NAME XTAL_CPU1_X32K_X1
J 0
(-6325 5085);
DISPLAY 0.489362 (-6325 5085);
WIRE 16 -1 (-6375 5025)(-5625 5025);
FORCEPROP 2 LAST SIG_NAME XTAL_CPU1_X32K_X2
J 0
(-6325 5035);
DISPLAY 0.489362 (-6325 5035);
WIRE 16 -1 (-6375 4675)(-5625 4675);
FORCEPROP 2 LAST SIG_NAME CPU1_NMI_SYNC_FLOOD_N
J 0
(-6325 4685);
DISPLAY 0.489362 (-6325 4685);
WIRE 16 -1 (-6375 5275)(-5625 5275);
FORCEPROP 2 LAST SIG_NAME XTAL_CPU1_X48M_X1
J 0
(-6325 5285);
DISPLAY 0.489362 (-6325 5285);
WIRE 16 -1 (-6375 5575)(-5625 5575);
FORCEPROP 2 LAST SIG_NAME RST_CPU1_SYS_N
J 2
(-6010 5585);
DISPLAY 0.489362 (-6010 5585);
WIRE 16 -1 (-5625 5625)(-6375 5625);
FORCEPROP 2 LAST SIG_NAME NC_CPU1_PWR_BTN_N
J 0
(-6325 5635);
DISPLAY 0.489362 (-6325 5635);
FORCEPROP 2 LASTPROP $XRERR UNIQUE?
J 0
(-6615 5625);
DISPLAY 0.638298 (-6615 5625);
PAINT MONO (-6615 5625);
DISPLAY INVISIBLE (-6615 5625);
WIRE 16 -1 (-6800 4425)(-5625 4425);
FORCEPROP 2 LAST SIG_NAME I3C_0_SPD_DDRAF_CPU1_R_SCL
J 2
(-5785 4435);
DISPLAY 0.489362 (-5785 4435);
WIRE 16 -1 (-3125 5175)(-2325 5175);
FORCEPROP 2 LAST SIG_NAME RST_CPU1_PERST0_N
J 0
(-2860 5185);
DISPLAY 0.489362 (-2860 5185);
WIRE 16 -1 (-3125 5125)(-2325 5125);
FORCEPROP 2 LAST SIG_NAME RST_CPU1_PERST1_N
J 0
(-2860 5135);
DISPLAY 0.489362 (-2860 5135);
WIRE 16 -1 (-3125 4925)(-2100 4925);
FORCEPROP 2 LAST SIG_NAME CLK_100M_CPU1_CLK01_R_DP
J 0
(-3035 4935);
DISPLAY 0.489362 (-3035 4935);
FORCEPROP 2 LASTPROP $XRERR UNIQUE?
J 0
(-3275 4935);
DISPLAY 0.638298 (-3275 4935);
PAINT MONO (-3275 4935);
DISPLAY INVISIBLE (-3275 4935);
WIRE 16 -1 (-3125 4775)(-2100 4775);
FORCEPROP 2 LAST SIG_NAME CLK_100M_CPU1_CLK02_R_DP
J 0
(-3035 4785);
DISPLAY 0.489362 (-3035 4785);
FORCEPROP 2 LASTPROP $XRERR UNIQUE?
J 0
(-3275 4785);
DISPLAY 0.638298 (-3275 4785);
PAINT MONO (-3275 4785);
DISPLAY INVISIBLE (-3275 4785);
WIRE 16 -1 (-1900 4925)(-725 4925);
FORCEPROP 2 LAST SIG_NAME CLK_100M_CPU1_CLK01_DP
J 0
(-1435 4935);
DISPLAY 0.489362 (-1435 4935);
WIRE 16 -1 (-1900 4875)(-725 4875);
FORCEPROP 2 LAST SIG_NAME CLK_100M_CPU1_CLK01_DN
J 0
(-1435 4885);
DISPLAY 0.489362 (-1435 4885);
WIRE 16 -1 (-1900 4775)(-725 4775);
FORCEPROP 2 LAST SIG_NAME CLK_100M_CPU1_CLK02_DP
J 0
(-1435 4785);
DISPLAY 0.489362 (-1435 4785);
WIRE 16 -1 (-1900 4725)(-725 4725);
FORCEPROP 2 LAST SIG_NAME CLK_100M_CPU1_CLK02_DN
J 0
(-1435 4735);
DISPLAY 0.489362 (-1435 4735);
WIRE 16 -1 (-1900 4625)(-725 4625);
FORCEPROP 2 LAST SIG_NAME CLK_100M_CPU1_CLK03_DP
J 0
(-1410 4635);
DISPLAY 0.489362 (-1410 4635);
WIRE 16 -1 (-1900 4575)(-725 4575);
FORCEPROP 2 LAST SIG_NAME CLK_100M_CPU1_CLK03_DN
J 0
(-1410 4585);
DISPLAY 0.489362 (-1410 4585);
WIRE 16 -1 (-4125 2175)(-2350 2175);
FORCEPROP 2 LAST SIG_NAME XTAL_CPU1_R_X32K_X1
J 0
(-3135 2185);
DISPLAY 0.489362 (-3135 2185);
FORCEPROP 2 LASTPROP $XRERR UNIQUE?
J 0
(-3375 2185);
DISPLAY 0.638298 (-3375 2185);
PAINT MONO (-3375 2185);
DISPLAY INVISIBLE (-3375 2185);
WIRE 16 -1 (-4125 1750)(-4125 2175);
WIRE 16 -1 (-3725 1750)(-4125 1750);
WIRE 16 -1 (-4125 1750)(-4125 1450);
WIRE 16 -1 (-3725 1450)(-4125 1450);
WIRE 16 -1 (-4125 1450)(-4125 1150);
WIRE 16 -1 (-3075 2125)(-2350 2125);
FORCEPROP 2 LAST SIG_NAME XTAL_CPU1_R_X32K_X2
J 0
(-3135 2135);
DISPLAY 0.489362 (-3135 2135);
FORCEPROP 2 LASTPROP $XRERR UNIQUE?
J 0
(-3375 2135);
DISPLAY 0.638298 (-3375 2135);
PAINT MONO (-3375 2135);
DISPLAY INVISIBLE (-3375 2135);
WIRE 16 -1 (-3075 2125)(-3075 1750);
WIRE 16 -1 (-3525 1750)(-3075 1750);
WIRE 16 -1 (-3075 1750)(-3075 1450);
WIRE 16 -1 (-3075 1450)(-3075 1175);
WIRE 16 -1 (-3525 1450)(-3075 1450);
WIRE 16 -1 (-3125 4625)(-2100 4625);
FORCEPROP 2 LAST SIG_NAME CLK_100M_CPU1_CLK03_R_DP
J 0
(-3035 4635);
DISPLAY 0.489362 (-3035 4635);
FORCEPROP 2 LASTPROP $XRERR UNIQUE?
J 0
(-3275 4635);
DISPLAY 0.638298 (-3275 4635);
PAINT MONO (-3275 4635);
DISPLAY INVISIBLE (-3275 4635);
WIRE 16 -1 (-3125 4875)(-2100 4875);
FORCEPROP 2 LAST SIG_NAME CLK_100M_CPU1_CLK01_R_DN
J 0
(-3035 4885);
DISPLAY 0.489362 (-3035 4885);
FORCEPROP 2 LASTPROP $XRERR UNIQUE?
J 0
(-3275 4885);
DISPLAY 0.638298 (-3275 4885);
PAINT MONO (-3275 4885);
DISPLAY INVISIBLE (-3275 4885);
WIRE 16 -1 (-3125 5625)(-2350 5625);
FORCEPROP 2 LAST SIG_NAME CPU1_PWRGD_OUT
J 0
(-2900 5635);
DISPLAY 0.489362 (-2900 5635);
WIRE 16 -1 (-3125 5525)(-1050 5525);
FORCEPROP 2 LAST SIG_NAME IRQ_WAKE_N
J 0
(-2910 5535);
DISPLAY 0.489362 (-2910 5535);
WIRE 16 -1 (-3125 5325)(-2350 5325);
FORCEPROP 2 LAST SIG_NAME CPU1_NV_SAVE_N
J 0
(-2900 5335);
DISPLAY 0.489362 (-2900 5335);
WIRE 16 -1 (-8525 1650)(-7675 1650);
FORCEPROP 2 LAST SIG_NAME CPU1_SLP_S3_N
J 0
(-8235 1660);
DISPLAY 0.489362 (-8235 1660);
WIRE 16 -1 (-6600 3325)(-5625 3325);
FORCEPROP 2 LAST SIG_NAME FM_BMC_READY_N
J 0
(-6575 3335);
DISPLAY 0.553191 (-6575 3335);
PAINT WHITE (-6575 3335);
WIRE 16 -1 (-6600 3275)(-5625 3275);
FORCEPROP 2 LAST SIG_NAME FM_BMC_TPM_PRES_N
J 0
(-6575 3285);
DISPLAY 0.553191 (-6575 3285);
PAINT WHITE (-6575 3285);
WIRE 16 -1 (-6650 3175)(-5625 3175);
FORCEPROP 2 LAST SIG_NAME TP_SLOT2_BUF_SKU_ID0
J 0
(-6575 3185);
DISPLAY 0.489362 (-6575 3185);
FORCEPROP 2 LASTPROP $XRERR UNIQUE?
J 0
(-6890 3175);
DISPLAY 0.638298 (-6890 3175);
PAINT MONO (-6890 3175);
DISPLAY INVISIBLE (-6890 3175);
WIRE 16 -1 (-6600 3225)(-5625 3225);
FORCEPROP 2 LAST SIG_NAME FM_CPU1_BMC_RST_N
J 0
(-6575 3235);
DISPLAY 0.489362 (-6575 3235);
WIRE 16 -1 (-7675 2200)(-8525 2200);
FORCEPROP 2 LAST SIG_NAME PWRGD_CPU1_PWROK
J 0
(-8235 2210);
DISPLAY 0.489362 (-8235 2210);
WIRE 16 -1 (-8525 2150)(-7675 2150);
FORCEPROP 2 LAST SIG_NAME CPU1_SMERR_N
J 0
(-8235 2160);
DISPLAY 0.489362 (-8235 2160);
WIRE 16 -1 (-8525 2250)(-7675 2250);
FORCEPROP 2 LAST SIG_NAME FM_CPU1_BMC_RST_N
J 0
(-8235 2260);
DISPLAY 0.489362 (-8235 2260);
WIRE 16 -1 (-9050 2900)(-9050 2675);
WIRE 16 -1 (-7675 2675)(-9050 2675);
FORCEPROP 2 LAST SIG_NAME I3C_1_SPD_DDRGL_CPU1_R_SDA
J 0
(-8235 2685);
DISPLAY 0.489362 (-8235 2685);
WIRE 16 -1 (-8875 2900)(-8875 2725);
WIRE 16 -1 (-7675 2725)(-8875 2725);
FORCEPROP 2 LAST SIG_NAME I3C_1_SPD_DDRGL_CPU1_R_SCL
J 0
(-8235 2735);
DISPLAY 0.489362 (-8235 2735);
WIRE 16 -1 (-8700 2900)(-8700 2775);
WIRE 16 -1 (-8700 2775)(-7675 2775);
FORCEPROP 2 LAST SIG_NAME I3C_0_SPD_DDRAF_CPU1_R_SDA
J 0
(-8235 2785);
DISPLAY 0.489362 (-8235 2785);
WIRE 16 -1 (-8525 2825)(-7675 2825);
FORCEPROP 2 LAST SIG_NAME I3C_0_SPD_DDRAF_CPU1_R_SCL
J 0
(-8235 2835);
DISPLAY 0.489362 (-8235 2835);
WIRE 16 -1 (-8525 2900)(-8525 2825);
DOT 1 (-8975 875);
DOT 1 (-8850 800);
DOT 1 (-8975 1700);
DOT 1 (-8975 1275);
DOT 1 (-8475 675);
DOT 1 (-8700 750);
DOT 1 (-8975 2100);
DOT 1 (-8975 2050);
DOT 1 (-8975 2250);
DOT 1 (-8975 1950);
DOT 1 (-8975 2200);
DOT 1 (-8850 1275);
DOT 1 (-3075 1450);
DOT 1 (-4125 1450);
DOT 1 (-7400 5525);
DOT 1 (-3075 1750);
DOT 1 (-4900 1650);
DOT 1 (-4125 1750);
DOT 1 (-4900 1050);
DOT 1 (-6175 1650);
DOT 1 (-1925 2175);
DOT 1 (-9100 950);
DOT 1 (-8700 1275);
DOT 1 (-8975 1850);
DOT 1 (-8975 1900);
DOT 1 (-8975 2000);
DOT 1 (-8975 2150);
DOT 1 (-8525 3150);
DOT 1 (-8700 3150);
DOT 1 (-8875 3150);
DOT 1 (-6175 1050);
QUIT
